FILE_TYPE = MACRO_DRAWING;
SET COLOR_WIRE YELLOW;
SET COLOR_PROP MONO;
SET COLOR_DOT WHITE;
SET COLOR_ARC YELLOW;
SET COLOR_BODY GREEN;
SET COLOR_NOTE MONO;
SET PROP_DISPLAY VALUE;
SET PAGE_NUMBER P127;
FORCEADD GND..1
(-3425 -2600);
FORCEPROP 3 LASTPIN (-3425 -2550) SIG_NAME GND\g
J 0
(-3415 -2540);
DISPLAY 0.659574 (-3415 -2540);
PAINT MONO (-3415 -2540);
DISPLAY INVISIBLE (-3415 -2540);
FORCEPROP 1 LAST PATH I14
J 0
(-3350 -2600);
DISPLAY 0.872340 (-3350 -2600);
PAINT AQUA (-3350 -2600);
DISPLAY INVISIBLE (-3350 -2600);
FORCEPROP 1 LAST BODY_TYPE PLUMBING
J 0
(-3470 -2643);
DISPLAY 0.340426 (-3470 -2643);
PAINT GREEN (-3470 -2643);
DISPLAY INVISIBLE (-3470 -2643);
FORCEPROP 1 LAST SIZE 1B
J 0
(-3350 -2650);
DISPLAY 1.404255 (-3350 -2650);
PAINT AQUA (-3350 -2650);
DISPLAY INVISIBLE (-3350 -2650);
FORCEPROP 2 LAST CDS_LIB mstr_symbols
J 0
(-3425 -2600);
PAINT ORANGE (-3425 -2600);
DISPLAY INVISIBLE (-3425 -2600);
FORCEPROP 1 LAST HDL_POWER GND
J 0
(-3425 -2450);
PAINT GREEN (-3425 -2450);
DISPLAY INVISIBLE (-3425 -2450);
FORCEPROP 1 LAST VOLTAGE 0.0V
J 0
(-3470 -2643);
DISPLAY 0.340426 (-3470 -2643);
PAINT SKYBLUE (-3470 -2643);
DISPLAY INVISIBLE (-3470 -2643);
FORCEADD P1V05_PCH_STBY..1
(-4275 -1700);
FORCEPROP 3 LASTPIN (-4275 -1750) SIG_NAME P1V05_PCH_STBY\g
J 0
(-4265 -1740);
DISPLAY 0.659574 (-4265 -1740);
PAINT MONO (-4265 -1740);
DISPLAY INVISIBLE (-4265 -1740);
FORCEPROP 1 LAST PATH I16
J 0
(-4225 -1675);
DISPLAY 0.872340 (-4225 -1675);
PAINT AQUA (-4225 -1675);
DISPLAY INVISIBLE (-4225 -1675);
FORCEPROP 1 LAST BODY_TYPE PLUMBING
J 0
(-4320 -1743);
DISPLAY 0.340426 (-4320 -1743);
PAINT GREEN (-4320 -1743);
DISPLAY INVISIBLE (-4320 -1743);
FORCEPROP 2 LAST CDS_LIB mstr_symbols
J 0
(-4275 -1700);
PAINT ORANGE (-4275 -1700);
DISPLAY INVISIBLE (-4275 -1700);
FORCEPROP 1 LAST HDL_POWER P1V05_PCH_STBY
J 0
(-4275 -1650);
DISPLAY 0.872340 (-4275 -1650);
PAINT GREEN (-4275 -1650);
DISPLAY INVISIBLE (-4275 -1650);
FORCEPROP 1 LAST VOLTAGE 1.05V
J 0
(-4320 -1743);
DISPLAY 0.340426 (-4320 -1743);
PAINT SKYBLUE (-4320 -1743);
DISPLAY INVISIBLE (-4320 -1743);
FORCEADD FERRITE..1
(-4025 -2050);
FORCEPROP 1 LASTPIN (-4125 -2050) $PN 1
J 2
(-4090 -2040);
DISPLAY 0.617021 (-4090 -2040);
PAINT WHITE (-4090 -2040);
FORCEPROP 1 LASTPIN (-3925 -2050) $PN 2
J 0
(-3945 -2040);
DISPLAY 0.617021 (-3945 -2040);
PAINT WHITE (-3945 -2040);
FORCEPROP 1 LAST MATERIAL FB
J 0
(-3970 -2150);
DISPLAY 0.617021 (-3970 -2150);
PAINT SKYBLUE (-3970 -2150);
FORCEPROP 1 LAST PACK_TYPE SM
J 0
(-3945 -2100);
DISPLAY 0.617021 (-3945 -2100);
PAINT SKYBLUE (-3945 -2100);
FORCEPROP 1 LAST VALUE 120
J 2
(-4020 -2150);
DISPLAY 0.617021 (-4020 -2150);
PAINT SKYBLUE (-4020 -2150);
FORCEPROP 1 LAST PART_NUMBER 693286-027
J 0
(-4120 -1935);
DISPLAY 0.617021 (-4120 -1935);
PAINT BLUE (-4120 -1935);
FORCEPROP 1 LAST LOCATION FB3M2
J 0
(-4120 -1995);
DISPLAY 0.617021 (-4120 -1995);
PAINT AQUA (-4120 -1995);
FORCEPROP 1 LAST PATH I17
J 0
(-4120 -1885);
DISPLAY 0.872340 (-4120 -1885);
PAINT PURPLE (-4120 -1885);
DISPLAY INVISIBLE (-4120 -1885);
FORCEPROP 2 LAST CDS_LOCATION FB3M2
J 0
(-4120 -1995);
DISPLAY 0.617021 (-4120 -1995);
PAINT AQUA (-4120 -1995);
DISPLAY INVISIBLE (-4120 -1995);
FORCEPROP 2 LAST SEC 1
J 0
(-4100 -1825);
PAINT MONO (-4100 -1825);
DISPLAY INVISIBLE (-4100 -1825);
FORCEPROP 2 LAST SEC_TYPE SM
J 0
(-4100 -1825);
DISPLAY 1.021277 (-4100 -1825);
PAINT ORANGE (-4100 -1825);
DISPLAY INVISIBLE (-4100 -1825);
FORCEPROP 2 LAST CDS_LIB mstr_discrete
J 0
(-4025 -2050);
PAINT ORANGE (-4025 -2050);
DISPLAY INVISIBLE (-4025 -2050);
FORCEPROP 2 LAST BOM_COST SB
J 0
(-4125 -1900);
DISPLAY 1.659574 (-4125 -1900);
PAINT WHITE (-4125 -1900);
DISPLAY INVISIBLE (-4125 -1900);
FORCEPROP 2 LAST ROOM SB_FILTER_PLL1
J 0
(-4125 -1900);
DISPLAY 1.659574 (-4125 -1900);
PAINT WHITE (-4125 -1900);
DISPLAY INVISIBLE (-4125 -1900);
FORCEADD CAP_A..1
R 2
(-4275 -2250);
FORCEPROP 1 LASTPIN (-4275 -2350) $PN 2
J 2
(-4285 -2370);
DISPLAY 0.617021 (-4285 -2370);
PAINT ORANGE (-4285 -2370);
FORCEPROP 1 LASTPIN (-4275 -2150) $PN 1
J 2
(-4285 -2170);
DISPLAY 0.617021 (-4285 -2170);
PAINT ORANGE (-4285 -2170);
FORCEPROP 1 LAST MATERIAL X6S
J 2
(-4325 -2350);
DISPLAY 0.617021 (-4325 -2350);
PAINT SKYBLUE (-4325 -2350);
FORCEPROP 1 LAST VOLTAGE 6.3V
J 2
(-4325 -2250);
DISPLAY 0.617021 (-4325 -2250);
PAINT SKYBLUE (-4325 -2250);
FORCEPROP 1 LAST PACK_TYPE 0402V
J 2
(-4325 -2450);
DISPLAY 0.617021 (-4325 -2450);
PAINT SKYBLUE (-4325 -2450);
FORCEPROP 1 LAST TOLERANCE 10%
J 2
(-4325 -2300);
DISPLAY 0.617021 (-4325 -2300);
PAINT SKYBLUE (-4325 -2300);
FORCEPROP 1 LAST VALUE 1.0UF
J 2
(-4325 -2200);
DISPLAY 0.617021 (-4325 -2200);
PAINT SKYBLUE (-4325 -2200);
FORCEPROP 1 LAST PART_NUMBER D97712-004
J 2
(-4325 -2400);
DISPLAY 0.617021 (-4325 -2400);
PAINT BLUE (-4325 -2400);
FORCEPROP 1 LAST LOCATION C3M22
J 2
(-4325 -2150);
DISPLAY 0.617021 (-4325 -2150);
PAINT AQUA (-4325 -2150);
FORCEPROP 1 LAST PATH I18
J 2
(-4325 -2100);
DISPLAY 0.978723 (-4325 -2100);
PAINT WHITE (-4325 -2100);
DISPLAY INVISIBLE (-4325 -2100);
FORCEPROP 2 LAST SEC 1
J 0
(-4325 -2050);
PAINT MONO (-4325 -2050);
DISPLAY INVISIBLE (-4325 -2050);
FORCEPROP 2 LAST SEC_TYPE 0402V
J 0
(-4325 -2050);
DISPLAY 1.021277 (-4325 -2050);
PAINT ORANGE (-4325 -2050);
DISPLAY INVISIBLE (-4325 -2050);
FORCEPROP 2 LAST CDS_SEC 1
J 0
(-4325 -2100);
PAINT ORANGE (-4325 -2100);
DISPLAY INVISIBLE (-4325 -2100);
FORCEPROP 2 LAST CDS_LIB dev_discrete
J 0
(-4275 -2250);
PAINT ORANGE (-4275 -2250);
DISPLAY INVISIBLE (-4275 -2250);
FORCEPROP 2 LAST BOM_COST SB
J 2
(-4325 -2100);
DISPLAY 1.659574 (-4325 -2100);
PAINT WHITE (-4325 -2100);
DISPLAY INVISIBLE (-4325 -2100);
FORCEPROP 2 LAST CDS_LOCATION C3M22
J 2
(-4325 -2150);
DISPLAY 0.617021 (-4325 -2150);
PAINT AQUA (-4325 -2150);
DISPLAY INVISIBLE (-4325 -2150);
FORCEPROP 2 LAST ROOM SB_FILTER_PLL1
J 2
(-4325 -2100);
DISPLAY 1.659574 (-4325 -2100);
PAINT WHITE (-4325 -2100);
DISPLAY INVISIBLE (-4325 -2100);
FORCEADD GND..1
(-3400 -3900);
FORCEPROP 3 LASTPIN (-3400 -3850) SIG_NAME GND\g
J 0
(-3390 -3840);
DISPLAY 0.659574 (-3390 -3840);
PAINT MONO (-3390 -3840);
DISPLAY INVISIBLE (-3390 -3840);
FORCEPROP 1 LAST PATH I23
J 0
(-3325 -3900);
DISPLAY 0.872340 (-3325 -3900);
PAINT AQUA (-3325 -3900);
DISPLAY INVISIBLE (-3325 -3900);
FORCEPROP 1 LAST BODY_TYPE PLUMBING
J 0
(-3445 -3943);
DISPLAY 0.340426 (-3445 -3943);
PAINT GREEN (-3445 -3943);
DISPLAY INVISIBLE (-3445 -3943);
FORCEPROP 1 LAST SIZE 1B
J 0
(-3325 -3950);
DISPLAY 1.404255 (-3325 -3950);
PAINT AQUA (-3325 -3950);
DISPLAY INVISIBLE (-3325 -3950);
FORCEPROP 2 LAST CDS_LIB mstr_symbols
J 0
(-3400 -3900);
PAINT ORANGE (-3400 -3900);
DISPLAY INVISIBLE (-3400 -3900);
FORCEPROP 1 LAST HDL_POWER GND
J 0
(-3400 -3750);
PAINT GREEN (-3400 -3750);
DISPLAY INVISIBLE (-3400 -3750);
FORCEPROP 1 LAST VOLTAGE 0.0V
J 0
(-3445 -3943);
DISPLAY 0.340426 (-3445 -3943);
PAINT SKYBLUE (-3445 -3943);
DISPLAY INVISIBLE (-3445 -3943);
FORCEADD P1V05_PCH_STBY..1
(-4250 -3000);
FORCEPROP 3 LASTPIN (-4250 -3050) SIG_NAME P1V05_PCH_STBY\g
J 0
(-4240 -3040);
DISPLAY 0.659574 (-4240 -3040);
PAINT MONO (-4240 -3040);
DISPLAY INVISIBLE (-4240 -3040);
FORCEPROP 1 LAST PATH I25
J 0
(-4200 -2975);
DISPLAY 0.872340 (-4200 -2975);
PAINT AQUA (-4200 -2975);
DISPLAY INVISIBLE (-4200 -2975);
FORCEPROP 1 LAST BODY_TYPE PLUMBING
J 0
(-4295 -3043);
DISPLAY 0.340426 (-4295 -3043);
PAINT GREEN (-4295 -3043);
DISPLAY INVISIBLE (-4295 -3043);
FORCEPROP 2 LAST CDS_LIB mstr_symbols
J 0
(-4250 -3000);
PAINT ORANGE (-4250 -3000);
DISPLAY INVISIBLE (-4250 -3000);
FORCEPROP 1 LAST HDL_POWER P1V05_PCH_STBY
J 0
(-4250 -2950);
DISPLAY 0.872340 (-4250 -2950);
PAINT GREEN (-4250 -2950);
DISPLAY INVISIBLE (-4250 -2950);
FORCEPROP 1 LAST VOLTAGE 1.05V
J 0
(-4295 -3043);
DISPLAY 0.340426 (-4295 -3043);
PAINT SKYBLUE (-4295 -3043);
DISPLAY INVISIBLE (-4295 -3043);
FORCEADD FERRITE..1
(-4000 -3350);
FORCEPROP 1 LASTPIN (-4100 -3350) $PN 1
J 2
(-4065 -3340);
DISPLAY 0.617021 (-4065 -3340);
PAINT WHITE (-4065 -3340);
FORCEPROP 1 LASTPIN (-3900 -3350) $PN 2
J 0
(-3920 -3340);
DISPLAY 0.617021 (-3920 -3340);
PAINT WHITE (-3920 -3340);
FORCEPROP 1 LAST MATERIAL FB
J 0
(-3945 -3450);
DISPLAY 0.617021 (-3945 -3450);
PAINT SKYBLUE (-3945 -3450);
FORCEPROP 1 LAST PACK_TYPE SM
J 0
(-3920 -3400);
DISPLAY 0.617021 (-3920 -3400);
PAINT SKYBLUE (-3920 -3400);
FORCEPROP 1 LAST VALUE 120
J 2
(-3995 -3450);
DISPLAY 0.617021 (-3995 -3450);
PAINT SKYBLUE (-3995 -3450);
FORCEPROP 1 LAST PART_NUMBER 693286-027
J 0
(-4095 -3235);
DISPLAY 0.617021 (-4095 -3235);
PAINT BLUE (-4095 -3235);
FORCEPROP 1 LAST LOCATION FB3M3
J 0
(-4095 -3295);
DISPLAY 0.617021 (-4095 -3295);
PAINT AQUA (-4095 -3295);
FORCEPROP 1 LAST PATH I26
J 0
(-4095 -3185);
DISPLAY 0.872340 (-4095 -3185);
PAINT PURPLE (-4095 -3185);
DISPLAY INVISIBLE (-4095 -3185);
FORCEPROP 2 LAST CDS_LOCATION FB3M3
J 0
(-4095 -3295);
DISPLAY 0.617021 (-4095 -3295);
PAINT AQUA (-4095 -3295);
DISPLAY INVISIBLE (-4095 -3295);
FORCEPROP 2 LAST SEC 1
J 0
(-4075 -3125);
PAINT MONO (-4075 -3125);
DISPLAY INVISIBLE (-4075 -3125);
FORCEPROP 2 LAST SEC_TYPE SM
J 0
(-4075 -3125);
DISPLAY 1.021277 (-4075 -3125);
PAINT ORANGE (-4075 -3125);
DISPLAY INVISIBLE (-4075 -3125);
FORCEPROP 2 LAST BOM_COST SB
J 0
(-4100 -3200);
DISPLAY 1.659574 (-4100 -3200);
PAINT WHITE (-4100 -3200);
DISPLAY INVISIBLE (-4100 -3200);
FORCEPROP 2 LAST CDS_LIB mstr_discrete
J 0
(-4000 -3350);
PAINT ORANGE (-4000 -3350);
DISPLAY INVISIBLE (-4000 -3350);
FORCEPROP 2 LAST ROOM SB_FILTER_XTAL
J 0
(-4100 -3200);
DISPLAY 1.659574 (-4100 -3200);
PAINT WHITE (-4100 -3200);
DISPLAY INVISIBLE (-4100 -3200);
FORCEADD CAP_A..1
R 2
(-4250 -3550);
FORCEPROP 1 LASTPIN (-4250 -3650) $PN 2
J 2
(-4260 -3670);
DISPLAY 0.617021 (-4260 -3670);
PAINT ORANGE (-4260 -3670);
FORCEPROP 1 LASTPIN (-4250 -3450) $PN 1
J 2
(-4260 -3470);
DISPLAY 0.617021 (-4260 -3470);
PAINT ORANGE (-4260 -3470);
FORCEPROP 1 LAST MATERIAL X6S
J 2
(-4300 -3650);
DISPLAY 0.617021 (-4300 -3650);
PAINT SKYBLUE (-4300 -3650);
FORCEPROP 1 LAST VOLTAGE 6.3V
J 2
(-4300 -3550);
DISPLAY 0.617021 (-4300 -3550);
PAINT SKYBLUE (-4300 -3550);
FORCEPROP 1 LAST PACK_TYPE 0402V
J 2
(-4300 -3750);
DISPLAY 0.617021 (-4300 -3750);
PAINT SKYBLUE (-4300 -3750);
FORCEPROP 1 LAST TOLERANCE 10%
J 2
(-4300 -3600);
DISPLAY 0.617021 (-4300 -3600);
PAINT SKYBLUE (-4300 -3600);
FORCEPROP 1 LAST VALUE 1.0UF
J 2
(-4300 -3500);
DISPLAY 0.617021 (-4300 -3500);
PAINT SKYBLUE (-4300 -3500);
FORCEPROP 1 LAST PART_NUMBER D97712-004
J 2
(-4300 -3700);
DISPLAY 0.617021 (-4300 -3700);
PAINT BLUE (-4300 -3700);
FORCEPROP 1 LAST LOCATION C3M30
J 2
(-4300 -3450);
DISPLAY 0.617021 (-4300 -3450);
PAINT AQUA (-4300 -3450);
FORCEPROP 1 LAST PATH I27
J 2
(-4300 -3400);
DISPLAY 0.978723 (-4300 -3400);
PAINT WHITE (-4300 -3400);
DISPLAY INVISIBLE (-4300 -3400);
FORCEPROP 2 LAST SEC 1
J 0
(-4300 -3350);
PAINT MONO (-4300 -3350);
DISPLAY INVISIBLE (-4300 -3350);
FORCEPROP 2 LAST SEC_TYPE 0402V
J 0
(-4300 -3350);
DISPLAY 1.021277 (-4300 -3350);
PAINT ORANGE (-4300 -3350);
DISPLAY INVISIBLE (-4300 -3350);
FORCEPROP 2 LAST CDS_SEC 1
J 0
(-4300 -3400);
PAINT ORANGE (-4300 -3400);
DISPLAY INVISIBLE (-4300 -3400);
FORCEPROP 2 LAST CDS_LIB dev_discrete
J 0
(-4250 -3550);
PAINT ORANGE (-4250 -3550);
DISPLAY INVISIBLE (-4250 -3550);
FORCEPROP 2 LAST BOM_COST SB
J 2
(-4300 -3400);
DISPLAY 1.659574 (-4300 -3400);
PAINT WHITE (-4300 -3400);
DISPLAY INVISIBLE (-4300 -3400);
FORCEPROP 2 LAST CDS_LOCATION C3M30
J 2
(-4300 -3450);
DISPLAY 0.617021 (-4300 -3450);
PAINT AQUA (-4300 -3450);
DISPLAY INVISIBLE (-4300 -3450);
FORCEPROP 2 LAST ROOM SB_FILTER_XTAL
J 2
(-4300 -3400);
DISPLAY 1.659574 (-4300 -3400);
PAINT WHITE (-4300 -3400);
DISPLAY INVISIBLE (-4300 -3400);
FORCEADD GND..1
(-2575 -1325);
FORCEPROP 3 LASTPIN (-2575 -1275) SIG_NAME GND\g
J 0
(-2565 -1265);
DISPLAY 0.659574 (-2565 -1265);
PAINT MONO (-2565 -1265);
DISPLAY INVISIBLE (-2565 -1265);
FORCEPROP 1 LAST PATH I32
J 0
(-2500 -1325);
DISPLAY 0.872340 (-2500 -1325);
PAINT AQUA (-2500 -1325);
DISPLAY INVISIBLE (-2500 -1325);
FORCEPROP 1 LAST BODY_TYPE PLUMBING
J 0
(-2620 -1368);
DISPLAY 0.340426 (-2620 -1368);
PAINT GREEN (-2620 -1368);
DISPLAY INVISIBLE (-2620 -1368);
FORCEPROP 1 LAST SIZE 1B
J 0
(-2500 -1375);
DISPLAY 1.404255 (-2500 -1375);
PAINT AQUA (-2500 -1375);
DISPLAY INVISIBLE (-2500 -1375);
FORCEPROP 2 LAST CDS_LIB mstr_symbols
J 0
(-2575 -1325);
PAINT ORANGE (-2575 -1325);
DISPLAY INVISIBLE (-2575 -1325);
FORCEPROP 1 LAST HDL_POWER GND
J 0
(-2575 -1175);
PAINT GREEN (-2575 -1175);
DISPLAY INVISIBLE (-2575 -1175);
FORCEPROP 1 LAST VOLTAGE 0.0V
J 0
(-2620 -1368);
DISPLAY 0.340426 (-2620 -1368);
PAINT SKYBLUE (-2620 -1368);
DISPLAY INVISIBLE (-2620 -1368);
FORCEADD GND..1
(-2575 -2600);
FORCEPROP 3 LASTPIN (-2575 -2550) SIG_NAME GND\g
J 0
(-2565 -2540);
DISPLAY 0.659574 (-2565 -2540);
PAINT MONO (-2565 -2540);
DISPLAY INVISIBLE (-2565 -2540);
FORCEPROP 1 LAST PATH I34
J 0
(-2500 -2600);
DISPLAY 0.872340 (-2500 -2600);
PAINT AQUA (-2500 -2600);
DISPLAY INVISIBLE (-2500 -2600);
FORCEPROP 1 LAST BODY_TYPE PLUMBING
J 0
(-2620 -2643);
DISPLAY 0.340426 (-2620 -2643);
PAINT GREEN (-2620 -2643);
DISPLAY INVISIBLE (-2620 -2643);
FORCEPROP 2 LAST CDS_LIB mstr_symbols
J 0
(-2575 -2600);
PAINT ORANGE (-2575 -2600);
DISPLAY INVISIBLE (-2575 -2600);
FORCEPROP 1 LAST SIZE 1B
J 0
(-2500 -2650);
DISPLAY 1.404255 (-2500 -2650);
PAINT AQUA (-2500 -2650);
DISPLAY INVISIBLE (-2500 -2650);
FORCEPROP 1 LAST HDL_POWER GND
J 0
(-2575 -2450);
PAINT GREEN (-2575 -2450);
DISPLAY INVISIBLE (-2575 -2450);
FORCEPROP 1 LAST VOLTAGE 0.0V
J 0
(-2620 -2643);
DISPLAY 0.340426 (-2620 -2643);
PAINT SKYBLUE (-2620 -2643);
DISPLAY INVISIBLE (-2620 -2643);
FORCEADD GND..1
(-2550 -3850);
FORCEPROP 3 LASTPIN (-2550 -3800) SIG_NAME GND\g
J 0
(-2540 -3790);
DISPLAY 0.659574 (-2540 -3790);
PAINT MONO (-2540 -3790);
DISPLAY INVISIBLE (-2540 -3790);
FORCEPROP 1 LAST PATH I36
J 0
(-2475 -3850);
DISPLAY 0.872340 (-2475 -3850);
PAINT AQUA (-2475 -3850);
DISPLAY INVISIBLE (-2475 -3850);
FORCEPROP 1 LAST BODY_TYPE PLUMBING
J 0
(-2595 -3893);
DISPLAY 0.340426 (-2595 -3893);
PAINT GREEN (-2595 -3893);
DISPLAY INVISIBLE (-2595 -3893);
FORCEPROP 1 LAST SIZE 1B
J 0
(-2475 -3900);
DISPLAY 1.404255 (-2475 -3900);
PAINT AQUA (-2475 -3900);
DISPLAY INVISIBLE (-2475 -3900);
FORCEPROP 2 LAST CDS_LIB mstr_symbols
J 0
(-2550 -3850);
PAINT ORANGE (-2550 -3850);
DISPLAY INVISIBLE (-2550 -3850);
FORCEPROP 1 LAST HDL_POWER GND
J 0
(-2550 -3700);
PAINT GREEN (-2550 -3700);
DISPLAY INVISIBLE (-2550 -3700);
FORCEPROP 1 LAST VOLTAGE 0.0V
J 0
(-2595 -3893);
DISPLAY 0.340426 (-2595 -3893);
PAINT SKYBLUE (-2595 -3893);
DISPLAY INVISIBLE (-2595 -3893);
FORCEADD P1V05_PCH_STBY_VCCA_XTAL..1
(-2550 -2975);
FORCEPROP 3 LASTPIN (-2550 -3025) SIG_NAME P1V05_PCH_STBY_VCCA_XTAL\g
J 0
(-2540 -3015);
DISPLAY 0.659574 (-2540 -3015);
PAINT MONO (-2540 -3015);
DISPLAY INVISIBLE (-2540 -3015);
FORCEPROP 1 LAST PATH I39
J 0
(-2500 -2950);
DISPLAY 0.872340 (-2500 -2950);
PAINT AQUA (-2500 -2950);
DISPLAY INVISIBLE (-2500 -2950);
FORCEPROP 1 LAST BODY_TYPE PLUMBING
J 0
(-2595 -3018);
DISPLAY 0.340426 (-2595 -3018);
PAINT GREEN (-2595 -3018);
DISPLAY INVISIBLE (-2595 -3018);
FORCEPROP 2 LAST CDS_LIB mstr_symbols
J 0
(-2550 -2975);
PAINT ORANGE (-2550 -2975);
DISPLAY INVISIBLE (-2550 -2975);
FORCEPROP 2 LAST BOM_COST SB
J 0
(-2550 -2825);
PAINT MONO (-2550 -2825);
DISPLAY INVISIBLE (-2550 -2825);
FORCEPROP 2 LAST ROOM SB_DECOUPLING
J 0
(-2550 -2875);
DISPLAY 1.361702 (-2550 -2875);
PAINT WHITE (-2550 -2875);
DISPLAY INVISIBLE (-2550 -2875);
FORCEPROP 1 LAST HDL_POWER P1V05_PCH_STBY_VCCA_XTAL
J 1
(-2550 -2925);
DISPLAY 0.872340 (-2550 -2925);
PAINT GREEN (-2550 -2925);
DISPLAY INVISIBLE (-2550 -2925);
FORCEPROP 1 LAST VOLTAGE 1.05V
J 0
(-2595 -3018);
DISPLAY 0.340426 (-2595 -3018);
PAINT SKYBLUE (-2595 -3018);
DISPLAY INVISIBLE (-2595 -3018);
FORCEADD P1V05_PCH_STBY_WM20_PLL..1
(1850 -750);
FORCEPROP 3 LASTPIN (1850 -800) SIG_NAME P1V05_PCH_STBY_WM20_PLL\g
J 0
(1860 -790);
DISPLAY 0.659574 (1860 -790);
PAINT MONO (1860 -790);
DISPLAY INVISIBLE (1860 -790);
FORCEPROP 2 LAST BOM_COST SB
J 0
(1850 -600);
PAINT MONO (1850 -600);
DISPLAY INVISIBLE (1850 -600);
FORCEPROP 2 LAST CDS_LIB mstr_symbols
J 0
(1850 -750);
PAINT ORANGE (1850 -750);
DISPLAY INVISIBLE (1850 -750);
FORCEPROP 1 LAST BODY_TYPE PLUMBING
J 0
(1805 -793);
DISPLAY 0.340426 (1805 -793);
PAINT GREEN (1805 -793);
DISPLAY INVISIBLE (1805 -793);
FORCEPROP 1 LAST PATH I40
J 0
(1900 -725);
DISPLAY 0.872340 (1900 -725);
PAINT AQUA (1900 -725);
DISPLAY INVISIBLE (1900 -725);
FORCEPROP 2 LAST ROOM SB_DECOUPLING
J 0
(1850 -650);
DISPLAY 1.361702 (1850 -650);
PAINT WHITE (1850 -650);
DISPLAY INVISIBLE (1850 -650);
FORCEPROP 1 LAST HDL_POWER P1V05_PCH_STBY_WM20_PLL
J 1
(1850 -700);
DISPLAY 0.872340 (1850 -700);
PAINT GREEN (1850 -700);
DISPLAY INVISIBLE (1850 -700);
FORCEPROP 1 LAST VOLTAGE 1.05V
J 0
(1805 -793);
DISPLAY 0.340426 (1805 -793);
PAINT SKYBLUE (1805 -793);
DISPLAY INVISIBLE (1805 -793);
FORCEADD CAP..1
(1850 -1375);
FORCEPROP 1 LASTPIN (1850 -1275) $PN 1
J 0
(1860 -1295);
DISPLAY 0.617021 (1860 -1295);
PAINT ORANGE (1860 -1295);
FORCEPROP 1 LASTPIN (1850 -1475) $PN 2
J 0
(1860 -1495);
DISPLAY 0.617021 (1860 -1495);
PAINT ORANGE (1860 -1495);
FORCEPROP 1 LAST MATERIAL X6S
J 0
(1900 -1475);
DISPLAY 0.617021 (1900 -1475);
PAINT SKYBLUE (1900 -1475);
FORCEPROP 1 LAST VOLTAGE 4V
J 0
(1900 -1375);
DISPLAY 0.617021 (1900 -1375);
PAINT SKYBLUE (1900 -1375);
FORCEPROP 1 LAST PACK_TYPE 0603LF
J 0
(1900 -1575);
DISPLAY 0.617021 (1900 -1575);
PAINT SKYBLUE (1900 -1575);
FORCEPROP 1 LAST TOLERANCE 20%
J 0
(1900 -1425);
DISPLAY 0.617021 (1900 -1425);
PAINT SKYBLUE (1900 -1425);
FORCEPROP 1 LAST VALUE 10UF
J 0
(1900 -1325);
DISPLAY 0.617021 (1900 -1325);
PAINT SKYBLUE (1900 -1325);
FORCEPROP 1 LAST PART_NUMBER E15431-001
J 0
(1900 -1525);
DISPLAY 0.617021 (1900 -1525);
PAINT BLUE (1900 -1525);
FORCEPROP 1 LAST LOCATION C2M5
J 0
(1900 -1275);
DISPLAY 0.617021 (1900 -1275);
PAINT AQUA (1900 -1275);
FORCEPROP 1 LAST PATH I43
J 0
(1900 -1225);
DISPLAY 0.978723 (1900 -1225);
PAINT WHITE (1900 -1225);
DISPLAY INVISIBLE (1900 -1225);
FORCEPROP 2 LAST CDS_LOCATION C2M5
J 0
(1900 -1275);
DISPLAY 0.617021 (1900 -1275);
PAINT AQUA (1900 -1275);
DISPLAY INVISIBLE (1900 -1275);
FORCEPROP 2 LAST SEC 1
J 0
(1900 -1175);
DISPLAY 0.680851 (1900 -1175);
PAINT MONO (1900 -1175);
DISPLAY INVISIBLE (1900 -1175);
FORCEPROP 2 LAST SEC_TYPE 0603LF
J 0
(1900 -1175);
DISPLAY 1.021277 (1900 -1175);
PAINT ORANGE (1900 -1175);
DISPLAY INVISIBLE (1900 -1175);
FORCEPROP 2 LAST BOM_COST SB
J 0
(1900 -1225);
DISPLAY 1.659574 (1900 -1225);
PAINT WHITE (1900 -1225);
DISPLAY INVISIBLE (1900 -1225);
FORCEPROP 2 LAST CDS_LIB mstr_discrete
J 0
(1850 -1375);
PAINT ORANGE (1850 -1375);
DISPLAY INVISIBLE (1850 -1375);
FORCEPROP 2 LAST ROOM SB_FILTER_VM20
J 0
(1900 -1225);
DISPLAY 1.659574 (1900 -1225);
PAINT WHITE (1900 -1225);
DISPLAY INVISIBLE (1900 -1225);
FORCEADD CAP_A..1
(1400 -1375);
FORCEPROP 1 LASTPIN (1400 -1475) $PN 2
J 0
(1410 -1495);
DISPLAY 0.617021 (1410 -1495);
PAINT ORANGE (1410 -1495);
FORCEPROP 1 LASTPIN (1400 -1275) $PN 1
J 0
(1410 -1295);
DISPLAY 0.617021 (1410 -1295);
PAINT ORANGE (1410 -1295);
FORCEPROP 1 LAST MATERIAL X6S
J 0
(1450 -1475);
DISPLAY 0.617021 (1450 -1475);
PAINT SKYBLUE (1450 -1475);
FORCEPROP 1 LAST VOLTAGE 6.3V
J 0
(1450 -1375);
DISPLAY 0.617021 (1450 -1375);
PAINT SKYBLUE (1450 -1375);
FORCEPROP 1 LAST PACK_TYPE 0402V
J 0
(1450 -1575);
DISPLAY 0.617021 (1450 -1575);
PAINT SKYBLUE (1450 -1575);
FORCEPROP 1 LAST TOLERANCE 10%
J 0
(1450 -1425);
DISPLAY 0.617021 (1450 -1425);
PAINT SKYBLUE (1450 -1425);
FORCEPROP 1 LAST VALUE 1.0UF
J 0
(1450 -1325);
DISPLAY 0.617021 (1450 -1325);
PAINT SKYBLUE (1450 -1325);
FORCEPROP 1 LAST PART_NUMBER D97712-004
J 0
(1450 -1525);
DISPLAY 0.617021 (1450 -1525);
PAINT BLUE (1450 -1525);
FORCEPROP 1 LAST LOCATION C2M7
J 0
(1450 -1275);
DISPLAY 0.617021 (1450 -1275);
PAINT AQUA (1450 -1275);
FORCEPROP 1 LAST PATH I44
J 0
(1450 -1225);
DISPLAY 0.978723 (1450 -1225);
PAINT WHITE (1450 -1225);
DISPLAY INVISIBLE (1450 -1225);
FORCEPROP 2 LAST SEC 1
J 0
(1450 -1175);
DISPLAY 0.680851 (1450 -1175);
PAINT MONO (1450 -1175);
DISPLAY INVISIBLE (1450 -1175);
FORCEPROP 2 LAST SEC_TYPE 0402V
J 0
(1450 -1175);
DISPLAY 1.021277 (1450 -1175);
PAINT ORANGE (1450 -1175);
DISPLAY INVISIBLE (1450 -1175);
FORCEPROP 2 LAST CDS_SEC 1
J 0
(1450 -1225);
PAINT ORANGE (1450 -1225);
DISPLAY INVISIBLE (1450 -1225);
FORCEPROP 2 LAST CDS_LIB dev_discrete
J 0
(1400 -1375);
PAINT ORANGE (1400 -1375);
DISPLAY INVISIBLE (1400 -1375);
FORCEPROP 2 LAST BOM_COST SB
J 0
(1450 -1225);
DISPLAY 1.659574 (1450 -1225);
PAINT WHITE (1450 -1225);
DISPLAY INVISIBLE (1450 -1225);
FORCEPROP 2 LAST CDS_LOCATION C2M7
J 0
(1450 -1275);
DISPLAY 0.617021 (1450 -1275);
PAINT AQUA (1450 -1275);
DISPLAY INVISIBLE (1450 -1275);
FORCEPROP 2 LAST ROOM SB_FILTER_VM20
J 0
(1450 -1225);
DISPLAY 1.659574 (1450 -1225);
PAINT WHITE (1450 -1225);
DISPLAY INVISIBLE (1450 -1225);
FORCEADD P1V05_PCH_STBY..1
(950 -825);
FORCEPROP 3 LASTPIN (950 -875) SIG_NAME P1V05_PCH_STBY\g
J 0
(960 -865);
DISPLAY 0.659574 (960 -865);
PAINT MONO (960 -865);
DISPLAY INVISIBLE (960 -865);
FORCEPROP 1 LAST PATH I45
J 0
(1000 -800);
DISPLAY 0.872340 (1000 -800);
PAINT AQUA (1000 -800);
DISPLAY INVISIBLE (1000 -800);
FORCEPROP 1 LAST BODY_TYPE PLUMBING
J 0
(905 -868);
DISPLAY 0.340426 (905 -868);
PAINT GREEN (905 -868);
DISPLAY INVISIBLE (905 -868);
FORCEPROP 2 LAST CDS_LIB mstr_symbols
J 0
(950 -825);
PAINT ORANGE (950 -825);
DISPLAY INVISIBLE (950 -825);
FORCEPROP 1 LAST HDL_POWER P1V05_PCH_STBY
J 0
(950 -775);
DISPLAY 0.872340 (950 -775);
PAINT GREEN (950 -775);
DISPLAY INVISIBLE (950 -775);
FORCEPROP 1 LAST VOLTAGE 1.05V
J 0
(905 -868);
DISPLAY 0.340426 (905 -868);
PAINT SKYBLUE (905 -868);
DISPLAY INVISIBLE (905 -868);
FORCEADD FERRITE..1
(1150 -1175);
FORCEPROP 1 LASTPIN (1050 -1175) $PN 1
J 2
(1085 -1165);
DISPLAY 0.617021 (1085 -1165);
PAINT WHITE (1085 -1165);
FORCEPROP 1 LASTPIN (1250 -1175) $PN 2
J 0
(1230 -1165);
DISPLAY 0.617021 (1230 -1165);
PAINT WHITE (1230 -1165);
FORCEPROP 1 LAST MATERIAL FB
J 0
(1205 -1275);
DISPLAY 0.617021 (1205 -1275);
PAINT SKYBLUE (1205 -1275);
FORCEPROP 1 LAST PACK_TYPE SM
J 0
(1230 -1225);
DISPLAY 0.617021 (1230 -1225);
PAINT SKYBLUE (1230 -1225);
FORCEPROP 1 LAST VALUE 120
J 2
(1155 -1275);
DISPLAY 0.617021 (1155 -1275);
PAINT SKYBLUE (1155 -1275);
FORCEPROP 1 LAST PART_NUMBER 693286-027
J 0
(1055 -1060);
DISPLAY 0.617021 (1055 -1060);
PAINT BLUE (1055 -1060);
FORCEPROP 1 LAST LOCATION FB2M1
J 0
(1055 -1120);
DISPLAY 0.617021 (1055 -1120);
PAINT AQUA (1055 -1120);
FORCEPROP 1 LAST PATH I46
J 0
(1055 -1010);
DISPLAY 0.872340 (1055 -1010);
PAINT PURPLE (1055 -1010);
DISPLAY INVISIBLE (1055 -1010);
FORCEPROP 2 LAST CDS_LOCATION FB2M1
J 0
(1055 -1120);
DISPLAY 0.617021 (1055 -1120);
PAINT AQUA (1055 -1120);
DISPLAY INVISIBLE (1055 -1120);
FORCEPROP 2 LAST SEC 1
J 0
(1075 -950);
DISPLAY 0.680851 (1075 -950);
PAINT MONO (1075 -950);
DISPLAY INVISIBLE (1075 -950);
FORCEPROP 2 LAST CDS_LIB mstr_discrete
J 0
(1150 -1175);
PAINT ORANGE (1150 -1175);
DISPLAY INVISIBLE (1150 -1175);
FORCEPROP 2 LAST SEC_TYPE SM
J 0
(1075 -950);
DISPLAY 1.021277 (1075 -950);
PAINT ORANGE (1075 -950);
DISPLAY INVISIBLE (1075 -950);
FORCEPROP 2 LAST BOM_COST SB
J 0
(1050 -1025);
DISPLAY 1.659574 (1050 -1025);
PAINT WHITE (1050 -1025);
DISPLAY INVISIBLE (1050 -1025);
FORCEPROP 2 LAST ROOM SB_FILTER_VM20
J 0
(1050 -1025);
DISPLAY 1.659574 (1050 -1025);
PAINT WHITE (1050 -1025);
DISPLAY INVISIBLE (1050 -1025);
FORCEADD P1V05_PCH_STBY_WM26_PLL..1
(-500 -800);
FORCEPROP 3 LASTPIN (-500 -850) SIG_NAME P1V05_PCH_STBY_WM26_PLL\g
J 0
(-490 -840);
DISPLAY 0.659574 (-490 -840);
PAINT MONO (-490 -840);
DISPLAY INVISIBLE (-490 -840);
FORCEPROP 1 LAST PATH I47
J 0
(-450 -775);
DISPLAY 0.872340 (-450 -775);
PAINT AQUA (-450 -775);
DISPLAY INVISIBLE (-450 -775);
FORCEPROP 1 LAST BODY_TYPE PLUMBING
J 0
(-545 -843);
DISPLAY 0.340426 (-545 -843);
PAINT GREEN (-545 -843);
DISPLAY INVISIBLE (-545 -843);
FORCEPROP 2 LAST CDS_LIB mstr_symbols
J 0
(-500 -800);
PAINT ORANGE (-500 -800);
DISPLAY INVISIBLE (-500 -800);
FORCEPROP 2 LAST BOM_COST SB
J 0
(-500 -650);
PAINT MONO (-500 -650);
DISPLAY INVISIBLE (-500 -650);
FORCEPROP 2 LAST ROOM SB_DECOUPLING
J 0
(-500 -700);
DISPLAY 1.361702 (-500 -700);
PAINT WHITE (-500 -700);
DISPLAY INVISIBLE (-500 -700);
FORCEPROP 1 LAST HDL_POWER P1V05_PCH_STBY_WM26_PLL
J 1
(-500 -750);
DISPLAY 0.872340 (-500 -750);
PAINT GREEN (-500 -750);
DISPLAY INVISIBLE (-500 -750);
FORCEPROP 1 LAST VOLTAGE 1.05V
J 0
(-545 -843);
DISPLAY 0.340426 (-545 -843);
PAINT SKYBLUE (-545 -843);
DISPLAY INVISIBLE (-545 -843);
FORCEADD CAP..1
(-500 -1400);
FORCEPROP 1 LASTPIN (-500 -1300) $PN 1
J 0
(-490 -1320);
DISPLAY 0.617021 (-490 -1320);
PAINT ORANGE (-490 -1320);
FORCEPROP 1 LAST MATERIAL X6S
J 0
(-450 -1500);
DISPLAY 0.617021 (-450 -1500);
PAINT SKYBLUE (-450 -1500);
FORCEPROP 1 LAST VOLTAGE 4V
J 0
(-450 -1400);
DISPLAY 0.617021 (-450 -1400);
PAINT SKYBLUE (-450 -1400);
FORCEPROP 1 LAST VALUE 10UF
J 0
(-450 -1350);
DISPLAY 0.617021 (-450 -1350);
PAINT SKYBLUE (-450 -1350);
FORCEPROP 1 LAST LOCATION C2M10
J 0
(-450 -1300);
DISPLAY 0.617021 (-450 -1300);
PAINT AQUA (-450 -1300);
FORCEPROP 1 LAST TOLERANCE 20%
J 0
(-450 -1450);
DISPLAY 0.617021 (-450 -1450);
PAINT SKYBLUE (-450 -1450);
FORCEPROP 1 LAST PACK_TYPE 0603LF
J 0
(-450 -1600);
DISPLAY 0.617021 (-450 -1600);
PAINT SKYBLUE (-450 -1600);
FORCEPROP 1 LAST PART_NUMBER E15431-001
J 0
(-450 -1550);
DISPLAY 0.617021 (-450 -1550);
PAINT BLUE (-450 -1550);
FORCEPROP 1 LASTPIN (-500 -1500) $PN 2
J 0
(-490 -1520);
DISPLAY 0.617021 (-490 -1520);
PAINT ORANGE (-490 -1520);
FORCEPROP 1 LAST PATH I49
J 0
(-450 -1250);
DISPLAY 0.978723 (-450 -1250);
PAINT WHITE (-450 -1250);
DISPLAY INVISIBLE (-450 -1250);
FORCEPROP 2 LAST CDS_LOCATION C2M10
J 0
(-450 -1300);
DISPLAY 0.617021 (-450 -1300);
PAINT AQUA (-450 -1300);
DISPLAY INVISIBLE (-450 -1300);
FORCEPROP 2 LAST SEC 1
J 0
(-450 -1200);
DISPLAY 0.680851 (-450 -1200);
PAINT MONO (-450 -1200);
DISPLAY INVISIBLE (-450 -1200);
FORCEPROP 2 LAST CDS_LIB mstr_discrete
J 0
(-500 -1400);
PAINT ORANGE (-500 -1400);
DISPLAY INVISIBLE (-500 -1400);
FORCEPROP 2 LAST BOM_COST SB
J 0
(-450 -1250);
DISPLAY 1.659574 (-450 -1250);
PAINT WHITE (-450 -1250);
DISPLAY INVISIBLE (-450 -1250);
FORCEPROP 2 LAST SEC_TYPE 0603LF
J 0
(-450 -1200);
DISPLAY 1.021277 (-450 -1200);
PAINT ORANGE (-450 -1200);
DISPLAY INVISIBLE (-450 -1200);
FORCEPROP 2 LAST ROOM SB_FILTER_VM26
J 0
(-450 -1250);
DISPLAY 1.659574 (-450 -1250);
PAINT WHITE (-450 -1250);
DISPLAY INVISIBLE (-450 -1250);
FORCEADD CAP_A..1
(-1000 -1400);
FORCEPROP 1 LASTPIN (-1000 -1500) $PN 2
J 0
(-990 -1520);
DISPLAY 0.617021 (-990 -1520);
PAINT ORANGE (-990 -1520);
FORCEPROP 1 LASTPIN (-1000 -1300) $PN 1
J 0
(-990 -1320);
DISPLAY 0.617021 (-990 -1320);
PAINT ORANGE (-990 -1320);
FORCEPROP 1 LAST MATERIAL X6S
J 0
(-950 -1500);
DISPLAY 0.617021 (-950 -1500);
PAINT SKYBLUE (-950 -1500);
FORCEPROP 1 LAST VOLTAGE 6.3V
J 0
(-950 -1400);
DISPLAY 0.617021 (-950 -1400);
PAINT SKYBLUE (-950 -1400);
FORCEPROP 1 LAST PACK_TYPE 0402V
J 0
(-950 -1600);
DISPLAY 0.617021 (-950 -1600);
PAINT SKYBLUE (-950 -1600);
FORCEPROP 1 LAST TOLERANCE 10%
J 0
(-950 -1450);
DISPLAY 0.617021 (-950 -1450);
PAINT SKYBLUE (-950 -1450);
FORCEPROP 1 LAST VALUE 1.0UF
J 0
(-950 -1350);
DISPLAY 0.617021 (-950 -1350);
PAINT SKYBLUE (-950 -1350);
FORCEPROP 1 LAST PART_NUMBER D97712-004
J 0
(-950 -1550);
DISPLAY 0.617021 (-950 -1550);
PAINT BLUE (-950 -1550);
FORCEPROP 1 LAST LOCATION C2M9
J 0
(-950 -1300);
DISPLAY 0.617021 (-950 -1300);
PAINT AQUA (-950 -1300);
FORCEPROP 1 LAST PATH I50
J 0
(-950 -1250);
DISPLAY 0.978723 (-950 -1250);
PAINT WHITE (-950 -1250);
DISPLAY INVISIBLE (-950 -1250);
FORCEPROP 2 LAST SEC 1
J 0
(-950 -1200);
DISPLAY 0.680851 (-950 -1200);
PAINT MONO (-950 -1200);
DISPLAY INVISIBLE (-950 -1200);
FORCEPROP 2 LAST SEC_TYPE 0402V
J 0
(-950 -1200);
DISPLAY 1.021277 (-950 -1200);
PAINT ORANGE (-950 -1200);
DISPLAY INVISIBLE (-950 -1200);
FORCEPROP 2 LAST CDS_SEC 1
J 0
(-950 -1250);
PAINT ORANGE (-950 -1250);
DISPLAY INVISIBLE (-950 -1250);
FORCEPROP 2 LAST CDS_LIB dev_discrete
J 0
(-1000 -1400);
PAINT ORANGE (-1000 -1400);
DISPLAY INVISIBLE (-1000 -1400);
FORCEPROP 2 LAST BOM_COST SB
J 0
(-950 -1250);
DISPLAY 1.659574 (-950 -1250);
PAINT WHITE (-950 -1250);
DISPLAY INVISIBLE (-950 -1250);
FORCEPROP 2 LAST CDS_LOCATION C2M9
J 0
(-950 -1300);
DISPLAY 0.617021 (-950 -1300);
PAINT AQUA (-950 -1300);
DISPLAY INVISIBLE (-950 -1300);
FORCEPROP 2 LAST ROOM SB_FILTER_VM26
J 0
(-950 -1250);
DISPLAY 1.659574 (-950 -1250);
PAINT WHITE (-950 -1250);
DISPLAY INVISIBLE (-950 -1250);
FORCEADD GND..1
(1400 -1725);
FORCEPROP 3 LASTPIN (1400 -1675) SIG_NAME GND\g
J 0
(1410 -1665);
DISPLAY 0.659574 (1410 -1665);
PAINT MONO (1410 -1665);
DISPLAY INVISIBLE (1410 -1665);
FORCEPROP 1 LAST PATH I51
J 0
(1475 -1725);
DISPLAY 0.872340 (1475 -1725);
PAINT AQUA (1475 -1725);
DISPLAY INVISIBLE (1475 -1725);
FORCEPROP 1 LAST BODY_TYPE PLUMBING
J 0
(1355 -1768);
DISPLAY 0.340426 (1355 -1768);
PAINT GREEN (1355 -1768);
DISPLAY INVISIBLE (1355 -1768);
FORCEPROP 1 LAST SIZE 1B
J 0
(1475 -1775);
DISPLAY 1.404255 (1475 -1775);
PAINT AQUA (1475 -1775);
DISPLAY INVISIBLE (1475 -1775);
FORCEPROP 2 LAST CDS_LIB mstr_symbols
J 0
(1400 -1725);
PAINT MONO (1400 -1725);
DISPLAY INVISIBLE (1400 -1725);
FORCEPROP 1 LAST HDL_POWER GND
J 0
(1400 -1575);
PAINT GREEN (1400 -1575);
DISPLAY INVISIBLE (1400 -1575);
FORCEPROP 1 LAST VOLTAGE 0.0V
J 0
(1355 -1768);
DISPLAY 0.340426 (1355 -1768);
PAINT SKYBLUE (1355 -1768);
DISPLAY INVISIBLE (1355 -1768);
FORCEADD P1V05_PCH_STBY_ISCLK_PLL..1
(1700 -2700);
FORCEPROP 3 LASTPIN (1700 -2750) SIG_NAME P1V05_PCH_STBY_ISCLK_PLL\g
J 0
(1710 -2740);
DISPLAY 0.659574 (1710 -2740);
PAINT MONO (1710 -2740);
DISPLAY INVISIBLE (1710 -2740);
FORCEPROP 1 LAST PATH I52
J 0
(1750 -2675);
DISPLAY 0.872340 (1750 -2675);
PAINT AQUA (1750 -2675);
DISPLAY INVISIBLE (1750 -2675);
FORCEPROP 1 LAST BODY_TYPE PLUMBING
J 0
(1655 -2743);
DISPLAY 0.340426 (1655 -2743);
PAINT GREEN (1655 -2743);
DISPLAY INVISIBLE (1655 -2743);
FORCEPROP 2 LAST CDS_LIB mstr_symbols
J 0
(1700 -2700);
PAINT ORANGE (1700 -2700);
DISPLAY INVISIBLE (1700 -2700);
FORCEPROP 2 LAST BOM_COST SB
J 0
(1700 -2550);
PAINT MONO (1700 -2550);
DISPLAY INVISIBLE (1700 -2550);
FORCEPROP 2 LAST ROOM SB_DECOUPLING
J 0
(1700 -2600);
DISPLAY 1.361702 (1700 -2600);
PAINT WHITE (1700 -2600);
DISPLAY INVISIBLE (1700 -2600);
FORCEPROP 1 LAST HDL_POWER P1V05_PCH_STBY_ISCLK_PLL
J 1
(1700 -2650);
DISPLAY 0.872340 (1700 -2650);
PAINT GREEN (1700 -2650);
DISPLAY INVISIBLE (1700 -2650);
FORCEPROP 1 LAST VOLTAGE 1.05V
J 0
(1655 -2743);
DISPLAY 0.340426 (1655 -2743);
PAINT SKYBLUE (1655 -2743);
DISPLAY INVISIBLE (1655 -2743);
FORCEADD P1V05_PCH_STBY..1
(950 -2725);
FORCEPROP 3 LASTPIN (950 -2775) SIG_NAME P1V05_PCH_STBY\g
J 0
(960 -2765);
DISPLAY 0.659574 (960 -2765);
PAINT MONO (960 -2765);
DISPLAY INVISIBLE (960 -2765);
FORCEPROP 1 LAST PATH I55
J 0
(1000 -2700);
DISPLAY 0.872340 (1000 -2700);
PAINT AQUA (1000 -2700);
DISPLAY INVISIBLE (1000 -2700);
FORCEPROP 1 LAST BODY_TYPE PLUMBING
J 0
(905 -2768);
DISPLAY 0.340426 (905 -2768);
PAINT GREEN (905 -2768);
DISPLAY INVISIBLE (905 -2768);
FORCEPROP 2 LAST CDS_LIB mstr_symbols
J 0
(950 -2725);
PAINT ORANGE (950 -2725);
DISPLAY INVISIBLE (950 -2725);
FORCEPROP 1 LAST HDL_POWER P1V05_PCH_STBY
J 0
(950 -2675);
DISPLAY 0.872340 (950 -2675);
PAINT GREEN (950 -2675);
DISPLAY INVISIBLE (950 -2675);
FORCEPROP 1 LAST VOLTAGE 1.05V
J 0
(905 -2768);
DISPLAY 0.340426 (905 -2768);
PAINT SKYBLUE (905 -2768);
DISPLAY INVISIBLE (905 -2768);
FORCEADD FERRITE..1
(1150 -3075);
FORCEPROP 1 LASTPIN (1050 -3075) $PN 1
J 2
(1085 -3065);
DISPLAY 0.617021 (1085 -3065);
PAINT WHITE (1085 -3065);
FORCEPROP 1 LASTPIN (1250 -3075) $PN 2
J 0
(1230 -3065);
DISPLAY 0.617021 (1230 -3065);
PAINT WHITE (1230 -3065);
FORCEPROP 1 LAST MATERIAL FB
J 0
(1205 -3175);
DISPLAY 0.617021 (1205 -3175);
PAINT SKYBLUE (1205 -3175);
FORCEPROP 1 LAST PACK_TYPE SM
J 0
(1230 -3125);
DISPLAY 0.617021 (1230 -3125);
PAINT SKYBLUE (1230 -3125);
FORCEPROP 1 LAST VALUE 120
J 2
(1155 -3175);
DISPLAY 0.617021 (1155 -3175);
PAINT SKYBLUE (1155 -3175);
FORCEPROP 1 LAST PART_NUMBER 693286-027
J 0
(1055 -2960);
DISPLAY 0.617021 (1055 -2960);
PAINT BLUE (1055 -2960);
FORCEPROP 1 LAST LOCATION FB3M4
J 0
(1055 -3020);
DISPLAY 0.617021 (1055 -3020);
PAINT AQUA (1055 -3020);
FORCEPROP 1 LAST PATH I56
J 0
(1055 -2910);
DISPLAY 0.872340 (1055 -2910);
PAINT PURPLE (1055 -2910);
DISPLAY INVISIBLE (1055 -2910);
FORCEPROP 2 LAST CDS_LOCATION FB3M4
J 0
(1055 -3020);
DISPLAY 0.617021 (1055 -3020);
PAINT AQUA (1055 -3020);
DISPLAY INVISIBLE (1055 -3020);
FORCEPROP 2 LAST SEC 1
J 0
(1075 -2850);
DISPLAY 0.680851 (1075 -2850);
PAINT MONO (1075 -2850);
DISPLAY INVISIBLE (1075 -2850);
FORCEPROP 2 LAST CDS_LIB mstr_discrete
J 0
(1150 -3075);
PAINT ORANGE (1150 -3075);
DISPLAY INVISIBLE (1150 -3075);
FORCEPROP 2 LAST SEC_TYPE SM
J 0
(1075 -2850);
DISPLAY 1.021277 (1075 -2850);
PAINT ORANGE (1075 -2850);
DISPLAY INVISIBLE (1075 -2850);
FORCEPROP 2 LAST BOM_COST SB
J 0
(1050 -2925);
DISPLAY 1.659574 (1050 -2925);
PAINT WHITE (1050 -2925);
DISPLAY INVISIBLE (1050 -2925);
FORCEPROP 2 LAST ROOM SB_FILTER_ISCLK
J 0
(1050 -2925);
DISPLAY 1.659574 (1050 -2925);
PAINT WHITE (1050 -2925);
DISPLAY INVISIBLE (1050 -2925);
FORCEADD CAP_A..1
R 2
(950 -3275);
FORCEPROP 1 LASTPIN (950 -3375) $PN 2
J 2
(940 -3395);
DISPLAY 0.617021 (940 -3395);
PAINT ORANGE (940 -3395);
FORCEPROP 1 LASTPIN (950 -3175) $PN 1
J 2
(940 -3195);
DISPLAY 0.617021 (940 -3195);
PAINT ORANGE (940 -3195);
FORCEPROP 1 LAST MATERIAL X6S
J 2
(900 -3375);
DISPLAY 0.617021 (900 -3375);
PAINT SKYBLUE (900 -3375);
FORCEPROP 1 LAST VOLTAGE 6.3V
J 2
(900 -3275);
DISPLAY 0.617021 (900 -3275);
PAINT SKYBLUE (900 -3275);
FORCEPROP 1 LAST PACK_TYPE 0402V
J 2
(900 -3475);
DISPLAY 0.617021 (900 -3475);
PAINT SKYBLUE (900 -3475);
FORCEPROP 1 LAST TOLERANCE 10%
J 2
(900 -3325);
DISPLAY 0.617021 (900 -3325);
PAINT SKYBLUE (900 -3325);
FORCEPROP 1 LAST VALUE 1.0UF
J 2
(900 -3225);
DISPLAY 0.617021 (900 -3225);
PAINT SKYBLUE (900 -3225);
FORCEPROP 1 LAST PART_NUMBER D97712-004
J 2
(900 -3425);
DISPLAY 0.617021 (900 -3425);
PAINT BLUE (900 -3425);
FORCEPROP 1 LAST LOCATION C3M31
J 2
(900 -3175);
DISPLAY 0.617021 (900 -3175);
PAINT AQUA (900 -3175);
FORCEPROP 1 LAST PATH I57
J 2
(900 -3125);
DISPLAY 0.978723 (900 -3125);
PAINT WHITE (900 -3125);
DISPLAY INVISIBLE (900 -3125);
FORCEPROP 2 LAST SEC 1
J 0
(900 -3075);
DISPLAY 0.680851 (900 -3075);
PAINT MONO (900 -3075);
DISPLAY INVISIBLE (900 -3075);
FORCEPROP 2 LAST SEC_TYPE 0402V
J 0
(900 -3075);
DISPLAY 1.021277 (900 -3075);
PAINT ORANGE (900 -3075);
DISPLAY INVISIBLE (900 -3075);
FORCEPROP 2 LAST CDS_SEC 1
J 0
(900 -3125);
PAINT ORANGE (900 -3125);
DISPLAY INVISIBLE (900 -3125);
FORCEPROP 2 LAST CDS_LIB dev_discrete
J 0
(950 -3275);
PAINT ORANGE (950 -3275);
DISPLAY INVISIBLE (950 -3275);
FORCEPROP 2 LAST BOM_COST SB
J 2
(900 -3125);
DISPLAY 1.659574 (900 -3125);
PAINT WHITE (900 -3125);
DISPLAY INVISIBLE (900 -3125);
FORCEPROP 2 LAST CDS_LOCATION C3M31
J 2
(900 -3175);
DISPLAY 0.617021 (900 -3175);
PAINT AQUA (900 -3175);
DISPLAY INVISIBLE (900 -3175);
FORCEPROP 2 LAST ROOM SB_FILTER_ISCLK
J 2
(900 -3125);
DISPLAY 1.659574 (900 -3125);
PAINT WHITE (900 -3125);
DISPLAY INVISIBLE (900 -3125);
FORCEADD GND..1
(1700 -3625);
FORCEPROP 3 LASTPIN (1700 -3575) SIG_NAME GND\g
J 0
(1710 -3565);
DISPLAY 0.659574 (1710 -3565);
PAINT MONO (1710 -3565);
DISPLAY INVISIBLE (1710 -3565);
FORCEPROP 1 LAST PATH I58
J 0
(1775 -3625);
DISPLAY 0.872340 (1775 -3625);
PAINT AQUA (1775 -3625);
DISPLAY INVISIBLE (1775 -3625);
FORCEPROP 1 LAST BODY_TYPE PLUMBING
J 0
(1655 -3668);
DISPLAY 0.340426 (1655 -3668);
PAINT GREEN (1655 -3668);
DISPLAY INVISIBLE (1655 -3668);
FORCEPROP 2 LAST CDS_LIB mstr_symbols
J 0
(1700 -3625);
PAINT ORANGE (1700 -3625);
DISPLAY INVISIBLE (1700 -3625);
FORCEPROP 1 LAST SIZE 1B
J 0
(1775 -3675);
DISPLAY 1.404255 (1775 -3675);
PAINT AQUA (1775 -3675);
DISPLAY INVISIBLE (1775 -3675);
FORCEPROP 1 LAST HDL_POWER GND
J 0
(1700 -3475);
PAINT GREEN (1700 -3475);
DISPLAY INVISIBLE (1700 -3475);
FORCEPROP 1 LAST VOLTAGE 0.0V
J 0
(1655 -3668);
DISPLAY 0.340426 (1655 -3668);
PAINT SKYBLUE (1655 -3668);
DISPLAY INVISIBLE (1655 -3668);
FORCEADD GND..1
(950 -3675);
FORCEPROP 3 LASTPIN (950 -3625) SIG_NAME GND\g
J 0
(960 -3615);
DISPLAY 0.659574 (960 -3615);
PAINT MONO (960 -3615);
DISPLAY INVISIBLE (960 -3615);
FORCEPROP 1 LAST PATH I59
J 0
(1025 -3675);
DISPLAY 0.872340 (1025 -3675);
PAINT AQUA (1025 -3675);
DISPLAY INVISIBLE (1025 -3675);
FORCEPROP 1 LAST BODY_TYPE PLUMBING
J 0
(905 -3718);
DISPLAY 0.340426 (905 -3718);
PAINT GREEN (905 -3718);
DISPLAY INVISIBLE (905 -3718);
FORCEPROP 1 LAST SIZE 1B
J 0
(1025 -3725);
DISPLAY 1.404255 (1025 -3725);
PAINT AQUA (1025 -3725);
DISPLAY INVISIBLE (1025 -3725);
FORCEPROP 2 LAST CDS_LIB mstr_symbols
J 0
(950 -3675);
PAINT MONO (950 -3675);
DISPLAY INVISIBLE (950 -3675);
FORCEPROP 1 LAST HDL_POWER GND
J 0
(950 -3525);
PAINT GREEN (950 -3525);
DISPLAY INVISIBLE (950 -3525);
FORCEPROP 1 LAST VOLTAGE 0.0V
J 0
(905 -3718);
DISPLAY 0.340426 (905 -3718);
PAINT SKYBLUE (905 -3718);
DISPLAY INVISIBLE (905 -3718);
FORCEADD GND..1
(-3450 -1400);
FORCEPROP 3 LASTPIN (-3450 -1350) SIG_NAME GND\g
J 0
(-3440 -1340);
DISPLAY 0.659574 (-3440 -1340);
PAINT MONO (-3440 -1340);
DISPLAY INVISIBLE (-3440 -1340);
FORCEPROP 1 LAST PATH I6
J 0
(-3375 -1400);
DISPLAY 0.872340 (-3375 -1400);
PAINT AQUA (-3375 -1400);
DISPLAY INVISIBLE (-3375 -1400);
FORCEPROP 1 LAST BODY_TYPE PLUMBING
J 0
(-3495 -1443);
DISPLAY 0.340426 (-3495 -1443);
PAINT GREEN (-3495 -1443);
DISPLAY INVISIBLE (-3495 -1443);
FORCEPROP 2 LAST CDS_LIB mstr_symbols
J 0
(-3450 -1400);
PAINT ORANGE (-3450 -1400);
DISPLAY INVISIBLE (-3450 -1400);
FORCEPROP 1 LAST SIZE 1B
J 0
(-3375 -1450);
DISPLAY 1.404255 (-3375 -1450);
PAINT AQUA (-3375 -1450);
DISPLAY INVISIBLE (-3375 -1450);
FORCEPROP 1 LAST HDL_POWER GND
J 0
(-3450 -1250);
PAINT GREEN (-3450 -1250);
DISPLAY INVISIBLE (-3450 -1250);
FORCEPROP 1 LAST VOLTAGE 0.0V
J 0
(-3495 -1443);
DISPLAY 0.340426 (-3495 -1443);
PAINT SKYBLUE (-3495 -1443);
DISPLAY INVISIBLE (-3495 -1443);
FORCEADD GND..1
(-1000 -1750);
FORCEPROP 3 LASTPIN (-1000 -1700) SIG_NAME GND\g
J 0
(-990 -1690);
DISPLAY 0.659574 (-990 -1690);
PAINT MONO (-990 -1690);
DISPLAY INVISIBLE (-990 -1690);
FORCEPROP 1 LAST PATH I61
J 0
(-925 -1750);
DISPLAY 0.872340 (-925 -1750);
PAINT AQUA (-925 -1750);
DISPLAY INVISIBLE (-925 -1750);
FORCEPROP 1 LAST BODY_TYPE PLUMBING
J 0
(-1045 -1793);
DISPLAY 0.340426 (-1045 -1793);
PAINT GREEN (-1045 -1793);
DISPLAY INVISIBLE (-1045 -1793);
FORCEPROP 2 LAST CDS_LIB mstr_symbols
J 0
(-1000 -1750);
PAINT MONO (-1000 -1750);
DISPLAY INVISIBLE (-1000 -1750);
FORCEPROP 1 LAST SIZE 1B
J 0
(-925 -1800);
DISPLAY 1.404255 (-925 -1800);
PAINT AQUA (-925 -1800);
DISPLAY INVISIBLE (-925 -1800);
FORCEPROP 1 LAST HDL_POWER GND
J 0
(-1000 -1600);
PAINT GREEN (-1000 -1600);
DISPLAY INVISIBLE (-1000 -1600);
FORCEPROP 1 LAST VOLTAGE 0.0V
J 0
(-1045 -1793);
DISPLAY 0.340426 (-1045 -1793);
PAINT SKYBLUE (-1045 -1793);
DISPLAY INVISIBLE (-1045 -1793);
FORCEADD P1V05_PCH_STBY_KR_PLL..1
(-500 -2650);
FORCEPROP 3 LASTPIN (-500 -2700) SIG_NAME P1V05_PCH_STBY_KR_PLL\g
J 0
(-490 -2690);
DISPLAY 0.659574 (-490 -2690);
PAINT MONO (-490 -2690);
DISPLAY INVISIBLE (-490 -2690);
FORCEPROP 2 LAST BOM_COST SB
J 0
(-500 -2500);
PAINT MONO (-500 -2500);
DISPLAY INVISIBLE (-500 -2500);
FORCEPROP 2 LAST CDS_LIB mstr_symbols
J 0
(-500 -2650);
PAINT ORANGE (-500 -2650);
DISPLAY INVISIBLE (-500 -2650);
FORCEPROP 1 LAST BODY_TYPE PLUMBING
J 0
(-545 -2693);
DISPLAY 0.340426 (-545 -2693);
PAINT GREEN (-545 -2693);
DISPLAY INVISIBLE (-545 -2693);
FORCEPROP 1 LAST PATH I62
J 0
(-450 -2625);
DISPLAY 0.872340 (-450 -2625);
PAINT AQUA (-450 -2625);
DISPLAY INVISIBLE (-450 -2625);
FORCEPROP 2 LAST ROOM SB_DECOUPLING
J 0
(-500 -2550);
DISPLAY 1.361702 (-500 -2550);
PAINT WHITE (-500 -2550);
DISPLAY INVISIBLE (-500 -2550);
FORCEPROP 1 LAST HDL_POWER P1V05_PCH_STBY_KR_PLL
J 1
(-500 -2600);
DISPLAY 0.872340 (-500 -2600);
PAINT GREEN (-500 -2600);
DISPLAY INVISIBLE (-500 -2600);
FORCEPROP 1 LAST VOLTAGE 1.05V
J 0
(-545 -2693);
DISPLAY 0.340426 (-545 -2693);
PAINT SKYBLUE (-545 -2693);
DISPLAY INVISIBLE (-545 -2693);
FORCEADD CAP..1
(-500 -3300);
FORCEPROP 1 LASTPIN (-500 -3200) $PN 1
J 0
(-490 -3220);
DISPLAY 0.617021 (-490 -3220);
PAINT ORANGE (-490 -3220);
FORCEPROP 1 LASTPIN (-500 -3400) $PN 2
J 0
(-490 -3420);
DISPLAY 0.617021 (-490 -3420);
PAINT ORANGE (-490 -3420);
FORCEPROP 1 LAST MATERIAL X6S
J 0
(-450 -3400);
DISPLAY 0.617021 (-450 -3400);
PAINT SKYBLUE (-450 -3400);
FORCEPROP 1 LAST VOLTAGE 4V
J 0
(-450 -3300);
DISPLAY 0.617021 (-450 -3300);
PAINT SKYBLUE (-450 -3300);
FORCEPROP 1 LAST PACK_TYPE 0603LF
J 0
(-450 -3500);
DISPLAY 0.617021 (-450 -3500);
PAINT SKYBLUE (-450 -3500);
FORCEPROP 1 LAST TOLERANCE 20%
J 0
(-450 -3350);
DISPLAY 0.617021 (-450 -3350);
PAINT SKYBLUE (-450 -3350);
FORCEPROP 1 LAST VALUE 10UF
J 0
(-450 -3250);
DISPLAY 0.617021 (-450 -3250);
PAINT SKYBLUE (-450 -3250);
FORCEPROP 1 LAST PART_NUMBER E15431-001
J 0
(-450 -3450);
DISPLAY 0.617021 (-450 -3450);
PAINT BLUE (-450 -3450);
FORCEPROP 1 LAST LOCATION C2N6
J 0
(-450 -3200);
DISPLAY 0.617021 (-450 -3200);
PAINT AQUA (-450 -3200);
FORCEPROP 1 LAST PATH I64
J 0
(-450 -3150);
DISPLAY 0.978723 (-450 -3150);
PAINT WHITE (-450 -3150);
DISPLAY INVISIBLE (-450 -3150);
FORCEPROP 2 LAST CDS_LOCATION C2N6
J 0
(-450 -3200);
DISPLAY 0.617021 (-450 -3200);
PAINT AQUA (-450 -3200);
DISPLAY INVISIBLE (-450 -3200);
FORCEPROP 2 LAST SEC 1
J 0
(-450 -3100);
DISPLAY 0.680851 (-450 -3100);
PAINT MONO (-450 -3100);
DISPLAY INVISIBLE (-450 -3100);
FORCEPROP 2 LAST CDS_LIB mstr_discrete
J 0
(-500 -3300);
PAINT ORANGE (-500 -3300);
DISPLAY INVISIBLE (-500 -3300);
FORCEPROP 2 LAST BOM_COST SB
J 0
(-450 -3150);
DISPLAY 1.659574 (-450 -3150);
PAINT WHITE (-450 -3150);
DISPLAY INVISIBLE (-450 -3150);
FORCEPROP 2 LAST SEC_TYPE 0603LF
J 0
(-450 -3100);
DISPLAY 1.021277 (-450 -3100);
PAINT ORANGE (-450 -3100);
DISPLAY INVISIBLE (-450 -3100);
FORCEPROP 2 LAST ROOM SB_FILTER_KR_PLL
J 0
(-450 -3150);
DISPLAY 1.659574 (-450 -3150);
PAINT WHITE (-450 -3150);
DISPLAY INVISIBLE (-450 -3150);
FORCEADD CAP_A..1
(-1000 -3300);
FORCEPROP 1 LASTPIN (-1000 -3400) $PN 2
J 0
(-990 -3420);
DISPLAY 0.617021 (-990 -3420);
PAINT ORANGE (-990 -3420);
FORCEPROP 1 LASTPIN (-1000 -3200) $PN 1
J 0
(-990 -3220);
DISPLAY 0.617021 (-990 -3220);
PAINT ORANGE (-990 -3220);
FORCEPROP 1 LAST MATERIAL X6S
J 0
(-950 -3400);
DISPLAY 0.617021 (-950 -3400);
PAINT SKYBLUE (-950 -3400);
FORCEPROP 1 LAST VOLTAGE 6.3V
J 0
(-950 -3300);
DISPLAY 0.617021 (-950 -3300);
PAINT SKYBLUE (-950 -3300);
FORCEPROP 1 LAST PACK_TYPE 0402V
J 0
(-950 -3500);
DISPLAY 0.617021 (-950 -3500);
PAINT SKYBLUE (-950 -3500);
FORCEPROP 1 LAST TOLERANCE 10%
J 0
(-950 -3350);
DISPLAY 0.617021 (-950 -3350);
PAINT SKYBLUE (-950 -3350);
FORCEPROP 1 LAST VALUE 1.0UF
J 0
(-950 -3250);
DISPLAY 0.617021 (-950 -3250);
PAINT SKYBLUE (-950 -3250);
FORCEPROP 1 LAST PART_NUMBER D97712-004
J 0
(-950 -3450);
DISPLAY 0.617021 (-950 -3450);
PAINT BLUE (-950 -3450);
FORCEPROP 1 LAST LOCATION C2N5
J 0
(-950 -3200);
DISPLAY 0.617021 (-950 -3200);
PAINT AQUA (-950 -3200);
FORCEPROP 1 LAST PATH I65
J 0
(-950 -3150);
DISPLAY 0.978723 (-950 -3150);
PAINT WHITE (-950 -3150);
DISPLAY INVISIBLE (-950 -3150);
FORCEPROP 2 LAST SEC 1
J 0
(-950 -3100);
DISPLAY 0.680851 (-950 -3100);
PAINT MONO (-950 -3100);
DISPLAY INVISIBLE (-950 -3100);
FORCEPROP 2 LAST SEC_TYPE 0402V
J 0
(-950 -3100);
DISPLAY 1.021277 (-950 -3100);
PAINT ORANGE (-950 -3100);
DISPLAY INVISIBLE (-950 -3100);
FORCEPROP 2 LAST CDS_SEC 1
J 0
(-950 -3150);
PAINT ORANGE (-950 -3150);
DISPLAY INVISIBLE (-950 -3150);
FORCEPROP 2 LAST CDS_LIB dev_discrete
J 0
(-1000 -3300);
PAINT ORANGE (-1000 -3300);
DISPLAY INVISIBLE (-1000 -3300);
FORCEPROP 2 LAST BOM_COST SB
J 0
(-950 -3150);
DISPLAY 1.659574 (-950 -3150);
PAINT WHITE (-950 -3150);
DISPLAY INVISIBLE (-950 -3150);
FORCEPROP 2 LAST CDS_LOCATION C2N5
J 0
(-950 -3200);
DISPLAY 0.617021 (-950 -3200);
PAINT AQUA (-950 -3200);
DISPLAY INVISIBLE (-950 -3200);
FORCEPROP 2 LAST ROOM SB_FILTER_KR_PLL
J 0
(-950 -3150);
DISPLAY 1.659574 (-950 -3150);
PAINT WHITE (-950 -3150);
DISPLAY INVISIBLE (-950 -3150);
FORCEADD GND..1
(-500 -3650);
FORCEPROP 3 LASTPIN (-500 -3600) SIG_NAME GND\g
J 0
(-490 -3590);
DISPLAY 0.659574 (-490 -3590);
PAINT MONO (-490 -3590);
DISPLAY INVISIBLE (-490 -3590);
FORCEPROP 1 LAST PATH I66
J 0
(-425 -3650);
DISPLAY 0.872340 (-425 -3650);
PAINT AQUA (-425 -3650);
DISPLAY INVISIBLE (-425 -3650);
FORCEPROP 1 LAST BODY_TYPE PLUMBING
J 0
(-545 -3693);
DISPLAY 0.340426 (-545 -3693);
PAINT GREEN (-545 -3693);
DISPLAY INVISIBLE (-545 -3693);
FORCEPROP 1 LAST SIZE 1B
J 0
(-425 -3700);
DISPLAY 1.404255 (-425 -3700);
PAINT AQUA (-425 -3700);
DISPLAY INVISIBLE (-425 -3700);
FORCEPROP 2 LAST CDS_LIB mstr_symbols
J 0
(-500 -3650);
PAINT MONO (-500 -3650);
DISPLAY INVISIBLE (-500 -3650);
FORCEPROP 1 LAST HDL_POWER GND
J 0
(-500 -3500);
PAINT GREEN (-500 -3500);
DISPLAY INVISIBLE (-500 -3500);
FORCEPROP 1 LAST VOLTAGE 0.0V
J 0
(-545 -3693);
DISPLAY 0.340426 (-545 -3693);
PAINT SKYBLUE (-545 -3693);
DISPLAY INVISIBLE (-545 -3693);
FORCEADD P1V05_PCH_STBY..1
(-1450 -850);
FORCEPROP 3 LASTPIN (-1450 -900) SIG_NAME P1V05_PCH_STBY\g
J 0
(-1440 -890);
DISPLAY 0.659574 (-1440 -890);
PAINT MONO (-1440 -890);
DISPLAY INVISIBLE (-1440 -890);
FORCEPROP 1 LAST PATH I68
J 0
(-1400 -825);
DISPLAY 0.872340 (-1400 -825);
PAINT AQUA (-1400 -825);
DISPLAY INVISIBLE (-1400 -825);
FORCEPROP 1 LAST BODY_TYPE PLUMBING
J 0
(-1495 -893);
DISPLAY 0.340426 (-1495 -893);
PAINT GREEN (-1495 -893);
DISPLAY INVISIBLE (-1495 -893);
FORCEPROP 2 LAST CDS_LIB mstr_symbols
J 0
(-1450 -850);
PAINT ORANGE (-1450 -850);
DISPLAY INVISIBLE (-1450 -850);
FORCEPROP 1 LAST HDL_POWER P1V05_PCH_STBY
J 0
(-1450 -800);
DISPLAY 0.872340 (-1450 -800);
PAINT GREEN (-1450 -800);
DISPLAY INVISIBLE (-1450 -800);
FORCEPROP 1 LAST VOLTAGE 1.05V
J 0
(-1495 -893);
DISPLAY 0.340426 (-1495 -893);
PAINT SKYBLUE (-1495 -893);
DISPLAY INVISIBLE (-1495 -893);
FORCEADD FERRITE..1
(-1225 -1200);
FORCEPROP 1 LASTPIN (-1325 -1200) $PN 1
J 2
(-1290 -1190);
DISPLAY 0.617021 (-1290 -1190);
PAINT WHITE (-1290 -1190);
FORCEPROP 1 LASTPIN (-1125 -1200) $PN 2
J 0
(-1145 -1190);
DISPLAY 0.617021 (-1145 -1190);
PAINT WHITE (-1145 -1190);
FORCEPROP 1 LAST MATERIAL FB
J 0
(-1170 -1300);
DISPLAY 0.617021 (-1170 -1300);
PAINT SKYBLUE (-1170 -1300);
FORCEPROP 1 LAST PACK_TYPE SM
J 0
(-1145 -1250);
DISPLAY 0.617021 (-1145 -1250);
PAINT SKYBLUE (-1145 -1250);
FORCEPROP 1 LAST VALUE 120
J 2
(-1220 -1300);
DISPLAY 0.617021 (-1220 -1300);
PAINT SKYBLUE (-1220 -1300);
FORCEPROP 1 LAST PART_NUMBER 693286-027
J 0
(-1320 -1085);
DISPLAY 0.617021 (-1320 -1085);
PAINT BLUE (-1320 -1085);
FORCEPROP 1 LAST LOCATION FB2M2
J 0
(-1320 -1145);
DISPLAY 0.617021 (-1320 -1145);
PAINT AQUA (-1320 -1145);
FORCEPROP 1 LAST PATH I69
J 0
(-1320 -1035);
DISPLAY 0.872340 (-1320 -1035);
PAINT PURPLE (-1320 -1035);
DISPLAY INVISIBLE (-1320 -1035);
FORCEPROP 2 LAST CDS_LOCATION FB2M2
J 0
(-1320 -1145);
DISPLAY 0.617021 (-1320 -1145);
PAINT AQUA (-1320 -1145);
DISPLAY INVISIBLE (-1320 -1145);
FORCEPROP 2 LAST SEC 1
J 0
(-1300 -975);
DISPLAY 0.680851 (-1300 -975);
PAINT MONO (-1300 -975);
DISPLAY INVISIBLE (-1300 -975);
FORCEPROP 2 LAST CDS_LIB mstr_discrete
J 0
(-1225 -1200);
PAINT ORANGE (-1225 -1200);
DISPLAY INVISIBLE (-1225 -1200);
FORCEPROP 2 LAST BOM_COST SB
J 0
(-1325 -1050);
DISPLAY 1.659574 (-1325 -1050);
PAINT WHITE (-1325 -1050);
DISPLAY INVISIBLE (-1325 -1050);
FORCEPROP 2 LAST SEC_TYPE SM
J 0
(-1300 -975);
DISPLAY 1.021277 (-1300 -975);
PAINT ORANGE (-1300 -975);
DISPLAY INVISIBLE (-1300 -975);
FORCEPROP 2 LAST ROOM SB_FILTER_VM26
J 0
(-1325 -1050);
DISPLAY 1.659574 (-1325 -1050);
PAINT WHITE (-1325 -1050);
DISPLAY INVISIBLE (-1325 -1050);
FORCEADD P1V05_PCH_STBY..1
(-4300 -500);
FORCEPROP 3 LASTPIN (-4300 -550) SIG_NAME P1V05_PCH_STBY\g
J 0
(-4290 -540);
DISPLAY 0.659574 (-4290 -540);
PAINT MONO (-4290 -540);
DISPLAY INVISIBLE (-4290 -540);
FORCEPROP 1 LAST PATH I7
J 0
(-4250 -475);
DISPLAY 0.872340 (-4250 -475);
PAINT AQUA (-4250 -475);
DISPLAY INVISIBLE (-4250 -475);
FORCEPROP 1 LAST BODY_TYPE PLUMBING
J 0
(-4345 -543);
DISPLAY 0.340426 (-4345 -543);
PAINT GREEN (-4345 -543);
DISPLAY INVISIBLE (-4345 -543);
FORCEPROP 2 LAST CDS_LIB mstr_symbols
J 0
(-4300 -500);
PAINT ORANGE (-4300 -500);
DISPLAY INVISIBLE (-4300 -500);
FORCEPROP 1 LAST HDL_POWER P1V05_PCH_STBY
J 0
(-4300 -450);
DISPLAY 0.872340 (-4300 -450);
PAINT GREEN (-4300 -450);
DISPLAY INVISIBLE (-4300 -450);
FORCEPROP 1 LAST VOLTAGE 1.05V
J 0
(-4345 -543);
DISPLAY 0.340426 (-4345 -543);
PAINT SKYBLUE (-4345 -543);
DISPLAY INVISIBLE (-4345 -543);
FORCEADD P1V05_PCH_STBY..1
(-1450 -2725);
FORCEPROP 3 LASTPIN (-1450 -2775) SIG_NAME P1V05_PCH_STBY\g
J 0
(-1440 -2765);
DISPLAY 0.659574 (-1440 -2765);
PAINT MONO (-1440 -2765);
DISPLAY INVISIBLE (-1440 -2765);
FORCEPROP 1 LAST PATH I70
J 0
(-1400 -2700);
DISPLAY 0.872340 (-1400 -2700);
PAINT AQUA (-1400 -2700);
DISPLAY INVISIBLE (-1400 -2700);
FORCEPROP 1 LAST BODY_TYPE PLUMBING
J 0
(-1495 -2768);
DISPLAY 0.340426 (-1495 -2768);
PAINT GREEN (-1495 -2768);
DISPLAY INVISIBLE (-1495 -2768);
FORCEPROP 2 LAST CDS_LIB mstr_symbols
J 0
(-1450 -2725);
PAINT ORANGE (-1450 -2725);
DISPLAY INVISIBLE (-1450 -2725);
FORCEPROP 1 LAST HDL_POWER P1V05_PCH_STBY
J 0
(-1450 -2675);
DISPLAY 0.872340 (-1450 -2675);
PAINT GREEN (-1450 -2675);
DISPLAY INVISIBLE (-1450 -2675);
FORCEPROP 1 LAST VOLTAGE 1.05V
J 0
(-1495 -2768);
DISPLAY 0.340426 (-1495 -2768);
PAINT SKYBLUE (-1495 -2768);
DISPLAY INVISIBLE (-1495 -2768);
FORCEADD INDUCTOR..1
(-1250 -3100);
FORCEPROP 1 LASTPIN (-1350 -3100) $PN 1
J 0
(-1350 -3090);
DISPLAY 0.617021 (-1350 -3090);
PAINT WHITE (-1350 -3090);
FORCEPROP 1 LASTPIN (-1150 -3100) $PN 2
J 2
(-1140 -3090);
DISPLAY 0.617021 (-1140 -3090);
PAINT WHITE (-1140 -3090);
FORCEPROP 1 LAST MATERIAL IND
J 0
(-1235 -3185);
DISPLAY 0.617021 (-1235 -3185);
PAINT SKYBLUE (-1235 -3185);
FORCEPROP 1 LAST PACK_TYPE SMT
J 0
(-1135 -3185);
DISPLAY 0.617021 (-1135 -3185);
PAINT SKYBLUE (-1135 -3185);
FORCEPROP 1 LAST PART_NUMBER 721891-082
J 0
(-1350 -3000);
DISPLAY 0.617021 (-1350 -3000);
PAINT BLUE (-1350 -3000);
FORCEPROP 1 LAST LOCATION L2M1
J 0
(-1350 -3050);
DISPLAY 0.617021 (-1350 -3050);
PAINT AQUA (-1350 -3050);
FORCEPROP 1 LAST VALUE 0.022UH
J 2
(-1255 -3185);
DISPLAY 0.617021 (-1255 -3185);
PAINT SKYBLUE (-1255 -3185);
FORCEPROP 1 LAST PATH I71
J 0
(-1350 -2950);
DISPLAY 0.978723 (-1350 -2950);
PAINT ORANGE (-1350 -2950);
DISPLAY INVISIBLE (-1350 -2950);
FORCEPROP 2 LAST CDS_LOCATION L2M1
J 0
(-1350 -3050);
DISPLAY 0.617021 (-1350 -3050);
PAINT AQUA (-1350 -3050);
DISPLAY INVISIBLE (-1350 -3050);
FORCEPROP 2 LAST SEC 1
J 0
(-1350 -2900);
PAINT MONO (-1350 -2900);
DISPLAY INVISIBLE (-1350 -2900);
FORCEPROP 2 LAST SEC_TYPE SMT
J 0
(-1350 -2900);
DISPLAY 1.021277 (-1350 -2900);
PAINT ORANGE (-1350 -2900);
DISPLAY INVISIBLE (-1350 -2900);
FORCEPROP 2 LAST CDS_LIB mstr_discrete
J 0
(-1250 -3100);
PAINT ORANGE (-1250 -3100);
DISPLAY INVISIBLE (-1250 -3100);
FORCEPROP 2 LAST BOM_COST SB
J 0
(-1350 -2950);
DISPLAY 1.659574 (-1350 -2950);
PAINT WHITE (-1350 -2950);
DISPLAY INVISIBLE (-1350 -2950);
FORCEPROP 2 LAST ROOM SB_FILTER_KR_PLL
J 0
(-1350 -2950);
DISPLAY 1.659574 (-1350 -2950);
PAINT WHITE (-1350 -2950);
DISPLAY INVISIBLE (-1350 -2950);
FORCEADD P1V05_PCH_STBY_VCCA_PLL0..1
(-2575 -1675);
FORCEPROP 3 LASTPIN (-2575 -1725) SIG_NAME P1V05_PCH_STBY_VCCA_PLL0\g
J 0
(-2565 -1715);
DISPLAY 0.659574 (-2565 -1715);
PAINT MONO (-2565 -1715);
DISPLAY INVISIBLE (-2565 -1715);
FORCEPROP 1 LAST PATH I72
J 0
(-2525 -1650);
DISPLAY 0.872340 (-2525 -1650);
PAINT AQUA (-2525 -1650);
DISPLAY INVISIBLE (-2525 -1650);
FORCEPROP 1 LAST BODY_TYPE PLUMBING
J 0
(-2620 -1718);
DISPLAY 0.340426 (-2620 -1718);
PAINT GREEN (-2620 -1718);
DISPLAY INVISIBLE (-2620 -1718);
FORCEPROP 2 LAST CDS_LIB mstr_symbols
J 0
(-2575 -1675);
PAINT ORANGE (-2575 -1675);
DISPLAY INVISIBLE (-2575 -1675);
FORCEPROP 2 LAST BOM_COST SB
J 0
(-2575 -1525);
PAINT MONO (-2575 -1525);
DISPLAY INVISIBLE (-2575 -1525);
FORCEPROP 2 LAST ROOM SB_DECOUPLING
J 0
(-2575 -1575);
DISPLAY 1.361702 (-2575 -1575);
PAINT WHITE (-2575 -1575);
DISPLAY INVISIBLE (-2575 -1575);
FORCEPROP 1 LAST HDL_POWER P1V05_PCH_STBY_VCCA_PLL0
J 1
(-2575 -1625);
DISPLAY 0.872340 (-2575 -1625);
PAINT GREEN (-2575 -1625);
DISPLAY INVISIBLE (-2575 -1625);
FORCEPROP 1 LAST VOLTAGE 1.05V
J 0
(-2620 -1718);
DISPLAY 0.340426 (-2620 -1718);
PAINT SKYBLUE (-2620 -1718);
DISPLAY INVISIBLE (-2620 -1718);
FORCEADD P1V05_PCH_STBY_VCCA_PLL1..1
(-2575 -475);
FORCEPROP 3 LASTPIN (-2575 -525) SIG_NAME P1V05_PCH_STBY_VCCA_PLL1\g
J 0
(-2565 -515);
DISPLAY 0.659574 (-2565 -515);
PAINT MONO (-2565 -515);
DISPLAY INVISIBLE (-2565 -515);
FORCEPROP 1 LAST PATH I73
J 0
(-2525 -450);
DISPLAY 0.872340 (-2525 -450);
PAINT AQUA (-2525 -450);
DISPLAY INVISIBLE (-2525 -450);
FORCEPROP 1 LAST BODY_TYPE PLUMBING
J 0
(-2620 -518);
DISPLAY 0.340426 (-2620 -518);
PAINT GREEN (-2620 -518);
DISPLAY INVISIBLE (-2620 -518);
FORCEPROP 2 LAST CDS_LIB mstr_symbols
J 0
(-2575 -475);
PAINT ORANGE (-2575 -475);
DISPLAY INVISIBLE (-2575 -475);
FORCEPROP 2 LAST BOM_COST SB
J 0
(-2575 -325);
PAINT MONO (-2575 -325);
DISPLAY INVISIBLE (-2575 -325);
FORCEPROP 2 LAST ROOM SB_DECOUPLING
J 0
(-2575 -375);
DISPLAY 1.361702 (-2575 -375);
PAINT WHITE (-2575 -375);
DISPLAY INVISIBLE (-2575 -375);
FORCEPROP 1 LAST HDL_POWER P1V05_PCH_STBY_VCCA_PLL1
J 1
(-2575 -425);
DISPLAY 0.872340 (-2575 -425);
PAINT GREEN (-2575 -425);
DISPLAY INVISIBLE (-2575 -425);
FORCEPROP 1 LAST VOLTAGE 1.05V
J 0
(-2620 -518);
DISPLAY 0.340426 (-2620 -518);
PAINT SKYBLUE (-2620 -518);
DISPLAY INVISIBLE (-2620 -518);
FORCEADD CAP_A..1
R 2
(-1450 -1400);
FORCEPROP 1 LASTPIN (-1450 -1500) $PN 2
J 2
(-1460 -1520);
DISPLAY 0.617021 (-1460 -1520);
PAINT ORANGE (-1460 -1520);
FORCEPROP 1 LASTPIN (-1450 -1300) $PN 1
J 2
(-1460 -1320);
DISPLAY 0.617021 (-1460 -1320);
PAINT ORANGE (-1460 -1320);
FORCEPROP 1 LAST MATERIAL X6S
J 2
(-1500 -1500);
DISPLAY 0.617021 (-1500 -1500);
PAINT SKYBLUE (-1500 -1500);
FORCEPROP 1 LAST VOLTAGE 6.3V
J 2
(-1500 -1400);
DISPLAY 0.617021 (-1500 -1400);
PAINT SKYBLUE (-1500 -1400);
FORCEPROP 1 LAST PACK_TYPE 0402V
J 2
(-1500 -1600);
DISPLAY 0.617021 (-1500 -1600);
PAINT SKYBLUE (-1500 -1600);
FORCEPROP 1 LAST TOLERANCE 10%
J 2
(-1500 -1450);
DISPLAY 0.617021 (-1500 -1450);
PAINT SKYBLUE (-1500 -1450);
FORCEPROP 1 LAST VALUE 1.0UF
J 2
(-1500 -1350);
DISPLAY 0.617021 (-1500 -1350);
PAINT SKYBLUE (-1500 -1350);
FORCEPROP 1 LAST PART_NUMBER D97712-004
J 2
(-1500 -1550);
DISPLAY 0.617021 (-1500 -1550);
PAINT BLUE (-1500 -1550);
FORCEPROP 1 LAST LOCATION C2M8
J 2
(-1500 -1300);
DISPLAY 0.617021 (-1500 -1300);
PAINT AQUA (-1500 -1300);
FORCEPROP 1 LAST PATH I74
J 2
(-1500 -1250);
DISPLAY 0.978723 (-1500 -1250);
PAINT WHITE (-1500 -1250);
DISPLAY INVISIBLE (-1500 -1250);
FORCEPROP 2 LAST SEC 1
J 2
(-1500 -1200);
DISPLAY 0.680851 (-1500 -1200);
PAINT MONO (-1500 -1200);
DISPLAY INVISIBLE (-1500 -1200);
FORCEPROP 2 LAST SEC_TYPE 0402V
J 2
(-1500 -1200);
DISPLAY 1.021277 (-1500 -1200);
PAINT ORANGE (-1500 -1200);
DISPLAY INVISIBLE (-1500 -1200);
FORCEPROP 2 LAST CDS_SEC 1
J 2
(-1500 -1250);
PAINT ORANGE (-1500 -1250);
DISPLAY INVISIBLE (-1500 -1250);
FORCEPROP 2 LAST CDS_LIB dev_discrete
J 2
(-1450 -1400);
PAINT ORANGE (-1450 -1400);
DISPLAY INVISIBLE (-1450 -1400);
FORCEPROP 2 LAST BOM_COST SB
J 2
(-1500 -1250);
DISPLAY 1.659574 (-1500 -1250);
PAINT WHITE (-1500 -1250);
DISPLAY INVISIBLE (-1500 -1250);
FORCEPROP 2 LAST CDS_LOCATION C2M8
J 2
(-1500 -1300);
DISPLAY 0.617021 (-1500 -1300);
PAINT AQUA (-1500 -1300);
DISPLAY INVISIBLE (-1500 -1300);
FORCEPROP 2 LAST ROOM SB_FILTER_VM26
J 2
(-1500 -1250);
DISPLAY 1.659574 (-1500 -1250);
PAINT WHITE (-1500 -1250);
DISPLAY INVISIBLE (-1500 -1250);
FORCEADD GND..1
(-1450 -1750);
FORCEPROP 3 LASTPIN (-1450 -1700) SIG_NAME GND\g
J 0
(-1440 -1690);
DISPLAY 0.659574 (-1440 -1690);
PAINT MONO (-1440 -1690);
DISPLAY INVISIBLE (-1440 -1690);
FORCEPROP 1 LAST PATH I75
J 0
(-1375 -1750);
DISPLAY 0.872340 (-1375 -1750);
PAINT AQUA (-1375 -1750);
DISPLAY INVISIBLE (-1375 -1750);
FORCEPROP 1 LAST BODY_TYPE PLUMBING
J 0
(-1495 -1793);
DISPLAY 0.340426 (-1495 -1793);
PAINT GREEN (-1495 -1793);
DISPLAY INVISIBLE (-1495 -1793);
FORCEPROP 1 LAST SIZE 1B
J 0
(-1375 -1800);
DISPLAY 1.404255 (-1375 -1800);
PAINT AQUA (-1375 -1800);
DISPLAY INVISIBLE (-1375 -1800);
FORCEPROP 2 LAST CDS_LIB mstr_symbols
J 0
(-1450 -1750);
PAINT ORANGE (-1450 -1750);
DISPLAY INVISIBLE (-1450 -1750);
FORCEPROP 1 LAST HDL_POWER GND
J 0
(-1450 -1600);
PAINT GREEN (-1450 -1600);
DISPLAY INVISIBLE (-1450 -1600);
FORCEPROP 1 LAST VOLTAGE 0.0V
J 0
(-1495 -1793);
DISPLAY 0.340426 (-1495 -1793);
PAINT SKYBLUE (-1495 -1793);
DISPLAY INVISIBLE (-1495 -1793);
FORCEADD CAP_A..1
R 2
(950 -1375);
FORCEPROP 1 LASTPIN (950 -1475) $PN 2
J 2
(940 -1495);
DISPLAY 0.617021 (940 -1495);
PAINT ORANGE (940 -1495);
FORCEPROP 1 LASTPIN (950 -1275) $PN 1
J 2
(940 -1295);
DISPLAY 0.617021 (940 -1295);
PAINT ORANGE (940 -1295);
FORCEPROP 1 LAST MATERIAL X6S
J 2
(900 -1475);
DISPLAY 0.617021 (900 -1475);
PAINT SKYBLUE (900 -1475);
FORCEPROP 1 LAST VOLTAGE 6.3V
J 2
(900 -1375);
DISPLAY 0.617021 (900 -1375);
PAINT SKYBLUE (900 -1375);
FORCEPROP 1 LAST PACK_TYPE 0402V
J 2
(900 -1575);
DISPLAY 0.617021 (900 -1575);
PAINT SKYBLUE (900 -1575);
FORCEPROP 1 LAST TOLERANCE 10%
J 2
(900 -1425);
DISPLAY 0.617021 (900 -1425);
PAINT SKYBLUE (900 -1425);
FORCEPROP 1 LAST VALUE 1.0UF
J 2
(900 -1325);
DISPLAY 0.617021 (900 -1325);
PAINT SKYBLUE (900 -1325);
FORCEPROP 1 LAST PART_NUMBER D97712-004
J 2
(900 -1525);
DISPLAY 0.617021 (900 -1525);
PAINT BLUE (900 -1525);
FORCEPROP 1 LAST LOCATION C2M6
J 2
(900 -1275);
DISPLAY 0.617021 (900 -1275);
PAINT AQUA (900 -1275);
FORCEPROP 1 LAST PATH I76
J 2
(900 -1225);
DISPLAY 0.978723 (900 -1225);
PAINT WHITE (900 -1225);
DISPLAY INVISIBLE (900 -1225);
FORCEPROP 2 LAST SEC 1
J 2
(900 -1175);
DISPLAY 0.680851 (900 -1175);
PAINT MONO (900 -1175);
DISPLAY INVISIBLE (900 -1175);
FORCEPROP 2 LAST SEC_TYPE 0402V
J 2
(900 -1175);
DISPLAY 1.021277 (900 -1175);
PAINT ORANGE (900 -1175);
DISPLAY INVISIBLE (900 -1175);
FORCEPROP 2 LAST CDS_SEC 1
J 2
(900 -1225);
PAINT ORANGE (900 -1225);
DISPLAY INVISIBLE (900 -1225);
FORCEPROP 2 LAST CDS_LIB dev_discrete
J 2
(950 -1375);
PAINT ORANGE (950 -1375);
DISPLAY INVISIBLE (950 -1375);
FORCEPROP 2 LAST BOM_COST SB
J 2
(900 -1225);
DISPLAY 1.659574 (900 -1225);
PAINT WHITE (900 -1225);
DISPLAY INVISIBLE (900 -1225);
FORCEPROP 2 LAST CDS_LOCATION C2M6
J 2
(900 -1275);
DISPLAY 0.617021 (900 -1275);
PAINT AQUA (900 -1275);
DISPLAY INVISIBLE (900 -1275);
FORCEPROP 2 LAST ROOM SB_FILTER_VM20
J 2
(900 -1225);
DISPLAY 1.659574 (900 -1225);
PAINT WHITE (900 -1225);
DISPLAY INVISIBLE (900 -1225);
FORCEADD GND..1
(950 -1725);
FORCEPROP 3 LASTPIN (950 -1675) SIG_NAME GND\g
J 0
(960 -1665);
DISPLAY 0.659574 (960 -1665);
PAINT MONO (960 -1665);
DISPLAY INVISIBLE (960 -1665);
FORCEPROP 1 LAST PATH I77
J 0
(1025 -1725);
DISPLAY 0.872340 (1025 -1725);
PAINT AQUA (1025 -1725);
DISPLAY INVISIBLE (1025 -1725);
FORCEPROP 1 LAST BODY_TYPE PLUMBING
J 0
(905 -1768);
DISPLAY 0.340426 (905 -1768);
PAINT GREEN (905 -1768);
DISPLAY INVISIBLE (905 -1768);
FORCEPROP 2 LAST CDS_LIB mstr_symbols
J 0
(950 -1725);
PAINT ORANGE (950 -1725);
DISPLAY INVISIBLE (950 -1725);
FORCEPROP 1 LAST SIZE 1B
J 0
(1025 -1775);
DISPLAY 1.404255 (1025 -1775);
PAINT AQUA (1025 -1775);
DISPLAY INVISIBLE (1025 -1775);
FORCEPROP 1 LAST HDL_POWER GND
J 0
(950 -1575);
PAINT GREEN (950 -1575);
DISPLAY INVISIBLE (950 -1575);
FORCEPROP 1 LAST VOLTAGE 0.0V
J 0
(905 -1768);
DISPLAY 0.340426 (905 -1768);
PAINT SKYBLUE (905 -1768);
DISPLAY INVISIBLE (905 -1768);
FORCEADD CAP_A..1
R 2
(-1450 -3300);
FORCEPROP 1 LASTPIN (-1450 -3400) $PN 2
J 2
(-1460 -3420);
DISPLAY 0.617021 (-1460 -3420);
PAINT ORANGE (-1460 -3420);
FORCEPROP 1 LASTPIN (-1450 -3200) $PN 1
J 2
(-1460 -3220);
DISPLAY 0.617021 (-1460 -3220);
PAINT ORANGE (-1460 -3220);
FORCEPROP 1 LAST VOLTAGE 6.3V
J 2
(-1500 -3300);
DISPLAY 0.617021 (-1500 -3300);
PAINT SKYBLUE (-1500 -3300);
FORCEPROP 1 LAST PACK_TYPE 0402V
J 2
(-1500 -3500);
DISPLAY 0.617021 (-1500 -3500);
PAINT SKYBLUE (-1500 -3500);
FORCEPROP 1 LAST TOLERANCE 10%
J 2
(-1500 -3350);
DISPLAY 0.617021 (-1500 -3350);
PAINT SKYBLUE (-1500 -3350);
FORCEPROP 1 LAST VALUE 1.0UF
J 2
(-1500 -3250);
DISPLAY 0.617021 (-1500 -3250);
PAINT SKYBLUE (-1500 -3250);
FORCEPROP 1 LAST PART_NUMBER D97712-004
J 2
(-1500 -3450);
DISPLAY 0.617021 (-1500 -3450);
PAINT BLUE (-1500 -3450);
FORCEPROP 1 LAST LOCATION C2M25
J 2
(-1500 -3200);
DISPLAY 0.617021 (-1500 -3200);
PAINT AQUA (-1500 -3200);
FORCEPROP 1 LAST MATERIAL X6S
J 2
(-1500 -3400);
DISPLAY 0.617021 (-1500 -3400);
PAINT SKYBLUE (-1500 -3400);
FORCEPROP 1 LAST PATH I78
J 2
(-1500 -3150);
DISPLAY 0.978723 (-1500 -3150);
PAINT WHITE (-1500 -3150);
DISPLAY INVISIBLE (-1500 -3150);
FORCEPROP 2 LAST SEC 1
J 2
(-1500 -3100);
DISPLAY 0.680851 (-1500 -3100);
PAINT MONO (-1500 -3100);
DISPLAY INVISIBLE (-1500 -3100);
FORCEPROP 2 LAST SEC_TYPE 0402V
J 2
(-1500 -3100);
DISPLAY 1.021277 (-1500 -3100);
PAINT ORANGE (-1500 -3100);
DISPLAY INVISIBLE (-1500 -3100);
FORCEPROP 2 LAST CDS_SEC 1
J 2
(-1500 -3150);
PAINT ORANGE (-1500 -3150);
DISPLAY INVISIBLE (-1500 -3150);
FORCEPROP 2 LAST CDS_LIB dev_discrete
J 2
(-1450 -3300);
PAINT ORANGE (-1450 -3300);
DISPLAY INVISIBLE (-1450 -3300);
FORCEPROP 2 LAST BOM_COST SB
J 2
(-1500 -3150);
DISPLAY 1.659574 (-1500 -3150);
PAINT WHITE (-1500 -3150);
DISPLAY INVISIBLE (-1500 -3150);
FORCEPROP 2 LAST ROOM SB_FILTER_KR_PLL
J 2
(-1500 -3150);
DISPLAY 1.659574 (-1500 -3150);
PAINT WHITE (-1500 -3150);
DISPLAY INVISIBLE (-1500 -3150);
FORCEPROP 2 LAST CDS_LOCATION C2M25
J 2
(-1500 -3200);
DISPLAY 0.617021 (-1500 -3200);
PAINT AQUA (-1500 -3200);
DISPLAY INVISIBLE (-1500 -3200);
FORCEADD GND..1
(-1450 -3625);
FORCEPROP 3 LASTPIN (-1450 -3575) SIG_NAME GND\g
J 0
(-1440 -3565);
DISPLAY 0.659574 (-1440 -3565);
PAINT MONO (-1440 -3565);
DISPLAY INVISIBLE (-1440 -3565);
FORCEPROP 1 LAST PATH I79
J 0
(-1375 -3625);
DISPLAY 0.872340 (-1375 -3625);
PAINT AQUA (-1375 -3625);
DISPLAY INVISIBLE (-1375 -3625);
FORCEPROP 1 LAST BODY_TYPE PLUMBING
J 0
(-1495 -3668);
DISPLAY 0.340426 (-1495 -3668);
PAINT GREEN (-1495 -3668);
DISPLAY INVISIBLE (-1495 -3668);
FORCEPROP 1 LAST SIZE 1B
J 0
(-1375 -3675);
DISPLAY 1.404255 (-1375 -3675);
PAINT AQUA (-1375 -3675);
DISPLAY INVISIBLE (-1375 -3675);
FORCEPROP 2 LAST CDS_LIB mstr_symbols
J 0
(-1450 -3625);
PAINT ORANGE (-1450 -3625);
DISPLAY INVISIBLE (-1450 -3625);
FORCEPROP 1 LAST HDL_POWER GND
J 0
(-1450 -3475);
PAINT GREEN (-1450 -3475);
DISPLAY INVISIBLE (-1450 -3475);
FORCEPROP 1 LAST VOLTAGE 0.0V
J 0
(-1495 -3668);
DISPLAY 0.340426 (-1495 -3668);
PAINT SKYBLUE (-1495 -3668);
DISPLAY INVISIBLE (-1495 -3668);
FORCEADD FERRITE..1
(-4050 -850);
FORCEPROP 1 LASTPIN (-4150 -850) $PN 1
J 2
(-4115 -840);
DISPLAY 0.617021 (-4115 -840);
PAINT WHITE (-4115 -840);
FORCEPROP 1 LASTPIN (-3950 -850) $PN 2
J 0
(-3970 -840);
DISPLAY 0.617021 (-3970 -840);
PAINT WHITE (-3970 -840);
FORCEPROP 1 LAST MATERIAL FB
J 0
(-3995 -950);
DISPLAY 0.617021 (-3995 -950);
PAINT SKYBLUE (-3995 -950);
FORCEPROP 1 LAST PACK_TYPE SM
J 0
(-3970 -900);
DISPLAY 0.617021 (-3970 -900);
PAINT SKYBLUE (-3970 -900);
FORCEPROP 1 LAST VALUE 120
J 2
(-4045 -950);
DISPLAY 0.617021 (-4045 -950);
PAINT SKYBLUE (-4045 -950);
FORCEPROP 1 LAST PART_NUMBER 693286-027
J 0
(-4145 -735);
DISPLAY 0.617021 (-4145 -735);
PAINT BLUE (-4145 -735);
FORCEPROP 1 LAST LOCATION FB3M1
J 0
(-4145 -795);
DISPLAY 0.617021 (-4145 -795);
PAINT AQUA (-4145 -795);
FORCEPROP 1 LAST PATH I8
J 0
(-4145 -685);
DISPLAY 0.872340 (-4145 -685);
PAINT PURPLE (-4145 -685);
DISPLAY INVISIBLE (-4145 -685);
FORCEPROP 2 LAST CDS_LOCATION FB3M1
J 0
(-4145 -795);
DISPLAY 0.617021 (-4145 -795);
PAINT AQUA (-4145 -795);
DISPLAY INVISIBLE (-4145 -795);
FORCEPROP 2 LAST SEC 1
J 0
(-4125 -625);
PAINT MONO (-4125 -625);
DISPLAY INVISIBLE (-4125 -625);
FORCEPROP 2 LAST SEC_TYPE SM
J 0
(-4125 -625);
DISPLAY 1.021277 (-4125 -625);
PAINT ORANGE (-4125 -625);
DISPLAY INVISIBLE (-4125 -625);
FORCEPROP 2 LAST BOM_COST SB
J 0
(-4150 -700);
DISPLAY 1.659574 (-4150 -700);
PAINT WHITE (-4150 -700);
DISPLAY INVISIBLE (-4150 -700);
FORCEPROP 2 LAST CDS_LIB mstr_discrete
J 0
(-4050 -850);
PAINT ORANGE (-4050 -850);
DISPLAY INVISIBLE (-4050 -850);
FORCEPROP 2 LAST ROOM SB_FILTER_PLL0
J 0
(-4150 -700);
DISPLAY 1.659574 (-4150 -700);
PAINT WHITE (-4150 -700);
DISPLAY INVISIBLE (-4150 -700);
FORCEADD CAP_A..1
(1400 -3275);
FORCEPROP 1 LASTPIN (1400 -3175) $PN 1
J 0
(1410 -3195);
DISPLAY 0.617021 (1410 -3195);
PAINT ORANGE (1410 -3195);
FORCEPROP 1 LASTPIN (1400 -3375) $PN 2
J 0
(1410 -3395);
DISPLAY 0.617021 (1410 -3395);
PAINT ORANGE (1410 -3395);
FORCEPROP 1 LAST MATERIAL X6S
J 0
(1450 -3375);
DISPLAY 0.617021 (1450 -3375);
PAINT SKYBLUE (1450 -3375);
FORCEPROP 1 LAST VOLTAGE 6.3V
J 0
(1450 -3275);
DISPLAY 0.617021 (1450 -3275);
PAINT SKYBLUE (1450 -3275);
FORCEPROP 1 LAST PACK_TYPE 0402V
J 0
(1450 -3475);
DISPLAY 0.617021 (1450 -3475);
PAINT SKYBLUE (1450 -3475);
FORCEPROP 1 LAST TOLERANCE 10%
J 0
(1450 -3325);
DISPLAY 0.617021 (1450 -3325);
PAINT SKYBLUE (1450 -3325);
FORCEPROP 1 LAST VALUE 1.0UF
J 0
(1450 -3225);
DISPLAY 0.617021 (1450 -3225);
PAINT SKYBLUE (1450 -3225);
FORCEPROP 1 LAST PART_NUMBER D97712-004
J 0
(1450 -3425);
DISPLAY 0.617021 (1450 -3425);
PAINT BLUE (1450 -3425);
FORCEPROP 1 LAST LOCATION C3M29
J 0
(1450 -3175);
DISPLAY 0.617021 (1450 -3175);
PAINT AQUA (1450 -3175);
FORCEPROP 1 LAST PATH I80
J 0
(1450 -3125);
DISPLAY 0.978723 (1450 -3125);
PAINT WHITE (1450 -3125);
DISPLAY INVISIBLE (1450 -3125);
FORCEPROP 2 LAST CDS_LOCATION C3M29
J 0
(1450 -3175);
DISPLAY 0.617021 (1450 -3175);
PAINT AQUA (1450 -3175);
DISPLAY INVISIBLE (1450 -3175);
FORCEPROP 2 LAST BOM_COST SB
J 0
(1450 -3125);
DISPLAY 1.659574 (1450 -3125);
PAINT WHITE (1450 -3125);
DISPLAY INVISIBLE (1450 -3125);
FORCEPROP 2 LAST CDS_LIB dev_discrete
J 0
(1400 -3275);
PAINT ORANGE (1400 -3275);
DISPLAY INVISIBLE (1400 -3275);
FORCEPROP 2 LAST CDS_SEC 1
J 0
(1450 -3125);
PAINT ORANGE (1450 -3125);
DISPLAY INVISIBLE (1450 -3125);
FORCEPROP 2 LAST SEC_TYPE 0402V
J 0
(1450 -3075);
DISPLAY 1.021277 (1450 -3075);
PAINT ORANGE (1450 -3075);
DISPLAY INVISIBLE (1450 -3075);
FORCEPROP 2 LAST SEC 1
J 0
(1450 -3075);
DISPLAY 0.680851 (1450 -3075);
PAINT MONO (1450 -3075);
DISPLAY INVISIBLE (1450 -3075);
FORCEPROP 2 LAST ROOM SB_FILTER_ISCLK
J 0
(1450 -3125);
DISPLAY 1.659574 (1450 -3125);
PAINT WHITE (1450 -3125);
DISPLAY INVISIBLE (1450 -3125);
FORCEADD CAP..1
(1700 -3275);
FORCEPROP 1 LASTPIN (1700 -3175) $PN 1
J 0
(1710 -3195);
DISPLAY 0.617021 (1710 -3195);
PAINT ORANGE (1710 -3195);
FORCEPROP 1 LASTPIN (1700 -3375) $PN 2
J 0
(1710 -3395);
DISPLAY 0.617021 (1710 -3395);
PAINT ORANGE (1710 -3395);
FORCEPROP 1 LAST MATERIAL X6S
J 0
(1750 -3375);
DISPLAY 0.617021 (1750 -3375);
PAINT SKYBLUE (1750 -3375);
FORCEPROP 1 LAST VOLTAGE 4V
J 0
(1750 -3275);
DISPLAY 0.617021 (1750 -3275);
PAINT SKYBLUE (1750 -3275);
FORCEPROP 1 LAST PACK_TYPE 0603LF
J 0
(1750 -3475);
DISPLAY 0.617021 (1750 -3475);
PAINT SKYBLUE (1750 -3475);
FORCEPROP 1 LAST TOLERANCE 20%
J 0
(1750 -3325);
DISPLAY 0.617021 (1750 -3325);
PAINT SKYBLUE (1750 -3325);
FORCEPROP 1 LAST VALUE 10UF
J 0
(1750 -3225);
DISPLAY 0.617021 (1750 -3225);
PAINT SKYBLUE (1750 -3225);
FORCEPROP 1 LAST PART_NUMBER E15431-001
J 0
(1750 -3425);
DISPLAY 0.617021 (1750 -3425);
PAINT BLUE (1750 -3425);
FORCEPROP 1 LAST LOCATION C3M24
J 0
(1750 -3175);
DISPLAY 0.617021 (1750 -3175);
PAINT AQUA (1750 -3175);
FORCEPROP 2 LAST CDS_LOCATION C3M24
J 0
(1750 -3175);
DISPLAY 0.617021 (1750 -3175);
PAINT AQUA (1750 -3175);
DISPLAY INVISIBLE (1750 -3175);
FORCEPROP 2 LAST SEC 1
J 0
(1750 -3075);
DISPLAY 0.680851 (1750 -3075);
PAINT MONO (1750 -3075);
DISPLAY INVISIBLE (1750 -3075);
FORCEPROP 2 LAST CDS_LIB mstr_discrete
J 0
(1700 -3275);
PAINT ORANGE (1700 -3275);
DISPLAY INVISIBLE (1700 -3275);
FORCEPROP 2 LAST SEC_TYPE 0603LF
J 0
(1750 -3075);
DISPLAY 1.021277 (1750 -3075);
PAINT ORANGE (1750 -3075);
DISPLAY INVISIBLE (1750 -3075);
FORCEPROP 2 LAST BOM_COST SB
J 0
(1750 -3125);
DISPLAY 1.659574 (1750 -3125);
PAINT WHITE (1750 -3125);
DISPLAY INVISIBLE (1750 -3125);
FORCEPROP 0 LAST CDS_SEC 1
J 0
(1750 -3125);
PAINT ORANGE (1750 -3125);
DISPLAY INVISIBLE (1750 -3125);
FORCEPROP 1 LAST PATH I81
J 0
(1750 -3125);
DISPLAY 0.978723 (1750 -3125);
PAINT WHITE (1750 -3125);
DISPLAY INVISIBLE (1750 -3125);
FORCEPROP 2 LAST ROOM SB_FILTER_ISCLK
J 0
(1750 -3125);
DISPLAY 1.659574 (1750 -3125);
PAINT WHITE (1750 -3125);
DISPLAY INVISIBLE (1750 -3125);
FORCEADD CAP..1
(-2550 -3600);
FORCEPROP 1 LASTPIN (-2550 -3500) $PN 1
J 0
(-2540 -3520);
DISPLAY 0.617021 (-2540 -3520);
PAINT ORANGE (-2540 -3520);
FORCEPROP 1 LASTPIN (-2550 -3700) $PN 2
J 0
(-2540 -3720);
DISPLAY 0.617021 (-2540 -3720);
PAINT ORANGE (-2540 -3720);
FORCEPROP 1 LAST MATERIAL X6S
J 0
(-2500 -3700);
DISPLAY 0.617021 (-2500 -3700);
PAINT SKYBLUE (-2500 -3700);
FORCEPROP 1 LAST VOLTAGE 4V
J 0
(-2500 -3600);
DISPLAY 0.617021 (-2500 -3600);
PAINT SKYBLUE (-2500 -3600);
FORCEPROP 1 LAST PACK_TYPE 0603LF
J 0
(-2500 -3800);
DISPLAY 0.617021 (-2500 -3800);
PAINT SKYBLUE (-2500 -3800);
FORCEPROP 1 LAST TOLERANCE 20%
J 0
(-2500 -3650);
DISPLAY 0.617021 (-2500 -3650);
PAINT SKYBLUE (-2500 -3650);
FORCEPROP 1 LAST VALUE 10UF
J 0
(-2500 -3550);
DISPLAY 0.617021 (-2500 -3550);
PAINT SKYBLUE (-2500 -3550);
FORCEPROP 1 LAST PART_NUMBER E15431-001
J 0
(-2500 -3750);
DISPLAY 0.617021 (-2500 -3750);
PAINT BLUE (-2500 -3750);
FORCEPROP 1 LAST LOCATION C3M23
J 0
(-2500 -3500);
DISPLAY 0.617021 (-2500 -3500);
PAINT AQUA (-2500 -3500);
FORCEPROP 2 LAST CDS_LOCATION C3M23
J 0
(-2500 -3500);
DISPLAY 0.617021 (-2500 -3500);
PAINT AQUA (-2500 -3500);
DISPLAY INVISIBLE (-2500 -3500);
FORCEPROP 2 LAST SEC 1
J 0
(-2500 -3400);
PAINT MONO (-2500 -3400);
DISPLAY INVISIBLE (-2500 -3400);
FORCEPROP 2 LAST SEC_TYPE 0603LF
J 0
(-2500 -3400);
DISPLAY 1.021277 (-2500 -3400);
PAINT ORANGE (-2500 -3400);
DISPLAY INVISIBLE (-2500 -3400);
FORCEPROP 2 LAST CDS_LIB mstr_discrete
J 0
(-2550 -3600);
PAINT ORANGE (-2550 -3600);
DISPLAY INVISIBLE (-2550 -3600);
FORCEPROP 2 LAST BOM_COST SB
J 0
(-2500 -3450);
DISPLAY 1.659574 (-2500 -3450);
PAINT WHITE (-2500 -3450);
DISPLAY INVISIBLE (-2500 -3450);
FORCEPROP 0 LAST CDS_SEC 1
J 0
(-2500 -3450);
PAINT ORANGE (-2500 -3450);
DISPLAY INVISIBLE (-2500 -3450);
FORCEPROP 1 LAST PATH I82
J 0
(-2500 -3450);
DISPLAY 0.978723 (-2500 -3450);
PAINT WHITE (-2500 -3450);
DISPLAY INVISIBLE (-2500 -3450);
FORCEPROP 2 LAST ROOM SB_FILTER_XTAL
J 0
(-2500 -3450);
DISPLAY 1.659574 (-2500 -3450);
PAINT WHITE (-2500 -3450);
DISPLAY INVISIBLE (-2500 -3450);
FORCEADD CAP_A..1
(-3400 -3550);
FORCEPROP 1 LASTPIN (-3400 -3650) $PN 2
J 0
(-3390 -3670);
DISPLAY 0.617021 (-3390 -3670);
PAINT ORANGE (-3390 -3670);
FORCEPROP 1 LASTPIN (-3400 -3450) $PN 1
J 0
(-3390 -3470);
DISPLAY 0.617021 (-3390 -3470);
PAINT ORANGE (-3390 -3470);
FORCEPROP 1 LAST MATERIAL X6S
J 0
(-3350 -3650);
DISPLAY 0.617021 (-3350 -3650);
PAINT SKYBLUE (-3350 -3650);
FORCEPROP 1 LAST VOLTAGE 6.3V
J 0
(-3350 -3550);
DISPLAY 0.617021 (-3350 -3550);
PAINT SKYBLUE (-3350 -3550);
FORCEPROP 1 LAST PACK_TYPE 0402V
J 0
(-3350 -3750);
DISPLAY 0.617021 (-3350 -3750);
PAINT SKYBLUE (-3350 -3750);
FORCEPROP 1 LAST TOLERANCE 10%
J 0
(-3350 -3600);
DISPLAY 0.617021 (-3350 -3600);
PAINT SKYBLUE (-3350 -3600);
FORCEPROP 1 LAST VALUE 1.0UF
J 0
(-3350 -3500);
DISPLAY 0.617021 (-3350 -3500);
PAINT SKYBLUE (-3350 -3500);
FORCEPROP 1 LAST PART_NUMBER D97712-004
J 0
(-3350 -3700);
DISPLAY 0.617021 (-3350 -3700);
PAINT BLUE (-3350 -3700);
FORCEPROP 1 LAST LOCATION C3M27
J 0
(-3350 -3450);
DISPLAY 0.617021 (-3350 -3450);
PAINT AQUA (-3350 -3450);
FORCEPROP 2 LAST SEC 1
J 0
(-3350 -3350);
DISPLAY 0.680851 (-3350 -3350);
PAINT MONO (-3350 -3350);
DISPLAY INVISIBLE (-3350 -3350);
FORCEPROP 2 LAST SEC_TYPE 0402V
J 0
(-3350 -3350);
DISPLAY 1.021277 (-3350 -3350);
PAINT ORANGE (-3350 -3350);
DISPLAY INVISIBLE (-3350 -3350);
FORCEPROP 2 LAST CDS_SEC 1
J 0
(-3350 -3400);
PAINT ORANGE (-3350 -3400);
DISPLAY INVISIBLE (-3350 -3400);
FORCEPROP 2 LAST CDS_LIB dev_discrete
J 0
(-3400 -3550);
PAINT ORANGE (-3400 -3550);
DISPLAY INVISIBLE (-3400 -3550);
FORCEPROP 2 LAST BOM_COST SB
J 0
(-3350 -3400);
DISPLAY 1.659574 (-3350 -3400);
PAINT WHITE (-3350 -3400);
DISPLAY INVISIBLE (-3350 -3400);
FORCEPROP 2 LAST CDS_LOCATION C3M27
J 0
(-3350 -3450);
DISPLAY 0.617021 (-3350 -3450);
PAINT AQUA (-3350 -3450);
DISPLAY INVISIBLE (-3350 -3450);
FORCEPROP 1 LAST PATH I83
J 0
(-3350 -3400);
DISPLAY 0.978723 (-3350 -3400);
PAINT WHITE (-3350 -3400);
DISPLAY INVISIBLE (-3350 -3400);
FORCEPROP 2 LAST ROOM SB_FILTER_XTAL
J 0
(-3350 -3400);
DISPLAY 1.659574 (-3350 -3400);
PAINT WHITE (-3350 -3400);
DISPLAY INVISIBLE (-3350 -3400);
FORCEADD CAP_A..1
(-3425 -2250);
FORCEPROP 1 LASTPIN (-3425 -2150) $PN 1
J 0
(-3415 -2170);
DISPLAY 0.617021 (-3415 -2170);
PAINT ORANGE (-3415 -2170);
FORCEPROP 1 LASTPIN (-3425 -2350) $PN 2
J 0
(-3415 -2370);
DISPLAY 0.617021 (-3415 -2370);
PAINT ORANGE (-3415 -2370);
FORCEPROP 1 LAST VOLTAGE 6.3V
J 0
(-3375 -2250);
DISPLAY 0.617021 (-3375 -2250);
PAINT SKYBLUE (-3375 -2250);
FORCEPROP 1 LAST PACK_TYPE 0402V
J 0
(-3375 -2450);
DISPLAY 0.617021 (-3375 -2450);
PAINT SKYBLUE (-3375 -2450);
FORCEPROP 1 LAST TOLERANCE 10%
J 0
(-3375 -2300);
DISPLAY 0.617021 (-3375 -2300);
PAINT SKYBLUE (-3375 -2300);
FORCEPROP 1 LAST VALUE 1.0UF
J 0
(-3375 -2200);
DISPLAY 0.617021 (-3375 -2200);
PAINT SKYBLUE (-3375 -2200);
FORCEPROP 1 LAST PART_NUMBER D97712-004
J 0
(-3375 -2400);
DISPLAY 0.617021 (-3375 -2400);
PAINT BLUE (-3375 -2400);
FORCEPROP 1 LAST LOCATION C3M20
J 0
(-3375 -2150);
DISPLAY 0.617021 (-3375 -2150);
PAINT AQUA (-3375 -2150);
FORCEPROP 1 LAST MATERIAL X6S
J 0
(-3375 -2350);
DISPLAY 0.617021 (-3375 -2350);
PAINT SKYBLUE (-3375 -2350);
FORCEPROP 1 LAST PATH I84
J 0
(-3375 -2100);
DISPLAY 0.978723 (-3375 -2100);
PAINT WHITE (-3375 -2100);
DISPLAY INVISIBLE (-3375 -2100);
FORCEPROP 2 LAST CDS_LOCATION C3M20
J 0
(-3375 -2150);
DISPLAY 0.617021 (-3375 -2150);
PAINT AQUA (-3375 -2150);
DISPLAY INVISIBLE (-3375 -2150);
FORCEPROP 2 LAST BOM_COST SB
J 0
(-3375 -2100);
DISPLAY 1.659574 (-3375 -2100);
PAINT WHITE (-3375 -2100);
DISPLAY INVISIBLE (-3375 -2100);
FORCEPROP 2 LAST CDS_LIB dev_discrete
J 0
(-3425 -2250);
PAINT ORANGE (-3425 -2250);
DISPLAY INVISIBLE (-3425 -2250);
FORCEPROP 2 LAST CDS_SEC 1
J 0
(-3375 -2100);
PAINT ORANGE (-3375 -2100);
DISPLAY INVISIBLE (-3375 -2100);
FORCEPROP 2 LAST SEC_TYPE 0402V
J 0
(-3375 -2050);
DISPLAY 1.021277 (-3375 -2050);
PAINT ORANGE (-3375 -2050);
DISPLAY INVISIBLE (-3375 -2050);
FORCEPROP 2 LAST SEC 1
J 0
(-3375 -2050);
DISPLAY 0.680851 (-3375 -2050);
PAINT MONO (-3375 -2050);
DISPLAY INVISIBLE (-3375 -2050);
FORCEPROP 2 LAST ROOM SB_FILTER_PLL1
J 0
(-3375 -2100);
DISPLAY 1.659574 (-3375 -2100);
PAINT WHITE (-3375 -2100);
DISPLAY INVISIBLE (-3375 -2100);
FORCEADD CAP..1
(-2575 -2325);
FORCEPROP 1 LASTPIN (-2575 -2225) $PN 1
J 0
(-2565 -2245);
DISPLAY 0.617021 (-2565 -2245);
PAINT ORANGE (-2565 -2245);
FORCEPROP 1 LASTPIN (-2575 -2425) $PN 2
J 0
(-2565 -2445);
DISPLAY 0.617021 (-2565 -2445);
PAINT ORANGE (-2565 -2445);
FORCEPROP 1 LAST MATERIAL X6S
J 0
(-2525 -2425);
DISPLAY 0.617021 (-2525 -2425);
PAINT SKYBLUE (-2525 -2425);
FORCEPROP 1 LAST VOLTAGE 4V
J 0
(-2525 -2325);
DISPLAY 0.617021 (-2525 -2325);
PAINT SKYBLUE (-2525 -2325);
FORCEPROP 1 LAST PACK_TYPE 0603LF
J 0
(-2525 -2525);
DISPLAY 0.617021 (-2525 -2525);
PAINT SKYBLUE (-2525 -2525);
FORCEPROP 1 LAST TOLERANCE 20%
J 0
(-2525 -2375);
DISPLAY 0.617021 (-2525 -2375);
PAINT SKYBLUE (-2525 -2375);
FORCEPROP 1 LAST VALUE 10UF
J 0
(-2525 -2275);
DISPLAY 0.617021 (-2525 -2275);
PAINT SKYBLUE (-2525 -2275);
FORCEPROP 1 LAST PART_NUMBER E15431-001
J 0
(-2525 -2475);
DISPLAY 0.617021 (-2525 -2475);
PAINT BLUE (-2525 -2475);
FORCEPROP 1 LAST LOCATION C3M18
J 0
(-2525 -2225);
DISPLAY 0.617021 (-2525 -2225);
PAINT AQUA (-2525 -2225);
FORCEPROP 2 LAST CDS_LOCATION C3M18
J 0
(-2525 -2225);
DISPLAY 0.617021 (-2525 -2225);
PAINT AQUA (-2525 -2225);
DISPLAY INVISIBLE (-2525 -2225);
FORCEPROP 2 LAST SEC 1
J 0
(-2525 -2125);
PAINT MONO (-2525 -2125);
DISPLAY INVISIBLE (-2525 -2125);
FORCEPROP 2 LAST SEC_TYPE 0603LF
J 0
(-2525 -2125);
DISPLAY 1.021277 (-2525 -2125);
PAINT ORANGE (-2525 -2125);
DISPLAY INVISIBLE (-2525 -2125);
FORCEPROP 2 LAST BOM_COST SB
J 0
(-2525 -2175);
DISPLAY 1.659574 (-2525 -2175);
PAINT WHITE (-2525 -2175);
DISPLAY INVISIBLE (-2525 -2175);
FORCEPROP 2 LAST CDS_LIB mstr_discrete
J 0
(-2575 -2325);
PAINT ORANGE (-2575 -2325);
DISPLAY INVISIBLE (-2575 -2325);
FORCEPROP 0 LAST CDS_SEC 1
J 0
(-2525 -2175);
PAINT ORANGE (-2525 -2175);
DISPLAY INVISIBLE (-2525 -2175);
FORCEPROP 1 LAST PATH I85
J 0
(-2525 -2175);
DISPLAY 0.978723 (-2525 -2175);
PAINT WHITE (-2525 -2175);
DISPLAY INVISIBLE (-2525 -2175);
FORCEPROP 2 LAST ROOM SB_FILTER_PLL1
J 0
(-2525 -2175);
DISPLAY 1.659574 (-2525 -2175);
PAINT WHITE (-2525 -2175);
DISPLAY INVISIBLE (-2525 -2175);
FORCEADD CAP..1
(-2575 -1075);
FORCEPROP 1 LASTPIN (-2575 -1175) $PN 2
J 0
(-2565 -1195);
DISPLAY 0.617021 (-2565 -1195);
PAINT ORANGE (-2565 -1195);
FORCEPROP 1 LASTPIN (-2575 -975) $PN 1
J 0
(-2565 -995);
DISPLAY 0.617021 (-2565 -995);
PAINT ORANGE (-2565 -995);
FORCEPROP 1 LAST MATERIAL X6S
J 0
(-2525 -1175);
DISPLAY 0.617021 (-2525 -1175);
PAINT SKYBLUE (-2525 -1175);
FORCEPROP 1 LAST VOLTAGE 4V
J 0
(-2525 -1075);
DISPLAY 0.617021 (-2525 -1075);
PAINT SKYBLUE (-2525 -1075);
FORCEPROP 1 LAST PACK_TYPE 0603LF
J 0
(-2525 -1275);
DISPLAY 0.617021 (-2525 -1275);
PAINT SKYBLUE (-2525 -1275);
FORCEPROP 1 LAST TOLERANCE 20%
J 0
(-2525 -1125);
DISPLAY 0.617021 (-2525 -1125);
PAINT SKYBLUE (-2525 -1125);
FORCEPROP 1 LAST VALUE 10UF
J 0
(-2525 -1025);
DISPLAY 0.617021 (-2525 -1025);
PAINT SKYBLUE (-2525 -1025);
FORCEPROP 1 LAST PART_NUMBER E15431-001
J 0
(-2525 -1225);
DISPLAY 0.617021 (-2525 -1225);
PAINT BLUE (-2525 -1225);
FORCEPROP 1 LAST LOCATION C3M17
J 0
(-2525 -975);
DISPLAY 0.617021 (-2525 -975);
PAINT AQUA (-2525 -975);
FORCEPROP 1 LAST PATH I86
J 0
(-2525 -925);
DISPLAY 0.978723 (-2525 -925);
PAINT WHITE (-2525 -925);
DISPLAY INVISIBLE (-2525 -925);
FORCEPROP 0 LAST CDS_SEC 1
J 0
(-2525 -925);
PAINT ORANGE (-2525 -925);
DISPLAY INVISIBLE (-2525 -925);
FORCEPROP 2 LAST BOM_COST SB
J 0
(-2525 -925);
DISPLAY 1.659574 (-2525 -925);
PAINT WHITE (-2525 -925);
DISPLAY INVISIBLE (-2525 -925);
FORCEPROP 2 LAST CDS_LIB mstr_discrete
J 0
(-2575 -1075);
PAINT ORANGE (-2575 -1075);
DISPLAY INVISIBLE (-2575 -1075);
FORCEPROP 2 LAST SEC_TYPE 0603LF
J 0
(-2525 -875);
DISPLAY 1.021277 (-2525 -875);
PAINT ORANGE (-2525 -875);
DISPLAY INVISIBLE (-2525 -875);
FORCEPROP 2 LAST SEC 1
J 0
(-2525 -875);
PAINT MONO (-2525 -875);
DISPLAY INVISIBLE (-2525 -875);
FORCEPROP 2 LAST CDS_LOCATION C3M17
J 0
(-2525 -975);
DISPLAY 0.617021 (-2525 -975);
PAINT AQUA (-2525 -975);
DISPLAY INVISIBLE (-2525 -975);
FORCEPROP 2 LAST ROOM SB_FILTER_PLL0
J 0
(-2525 -925);
DISPLAY 1.659574 (-2525 -925);
PAINT WHITE (-2525 -925);
DISPLAY INVISIBLE (-2525 -925);
FORCEADD CAP_A..1
(-3450 -1050);
FORCEPROP 1 LASTPIN (-3450 -950) $PN 1
J 0
(-3440 -970);
DISPLAY 0.617021 (-3440 -970);
PAINT ORANGE (-3440 -970);
FORCEPROP 1 LASTPIN (-3450 -1150) $PN 2
J 0
(-3440 -1170);
DISPLAY 0.617021 (-3440 -1170);
PAINT ORANGE (-3440 -1170);
FORCEPROP 1 LAST MATERIAL X6S
J 0
(-3400 -1150);
DISPLAY 0.617021 (-3400 -1150);
PAINT SKYBLUE (-3400 -1150);
FORCEPROP 1 LAST VOLTAGE 6.3V
J 0
(-3400 -1050);
DISPLAY 0.617021 (-3400 -1050);
PAINT SKYBLUE (-3400 -1050);
FORCEPROP 1 LAST PACK_TYPE 0402V
J 0
(-3400 -1250);
DISPLAY 0.617021 (-3400 -1250);
PAINT SKYBLUE (-3400 -1250);
FORCEPROP 1 LAST TOLERANCE 10%
J 0
(-3400 -1100);
DISPLAY 0.617021 (-3400 -1100);
PAINT SKYBLUE (-3400 -1100);
FORCEPROP 1 LAST VALUE 1.0UF
J 0
(-3400 -1000);
DISPLAY 0.617021 (-3400 -1000);
PAINT SKYBLUE (-3400 -1000);
FORCEPROP 1 LAST PART_NUMBER D97712-004
J 0
(-3400 -1200);
DISPLAY 0.617021 (-3400 -1200);
PAINT BLUE (-3400 -1200);
FORCEPROP 1 LAST LOCATION C3M19
J 0
(-3400 -950);
DISPLAY 0.617021 (-3400 -950);
PAINT AQUA (-3400 -950);
FORCEPROP 2 LAST CDS_LOCATION C3M19
J 0
(-3400 -950);
DISPLAY 0.617021 (-3400 -950);
PAINT AQUA (-3400 -950);
DISPLAY INVISIBLE (-3400 -950);
FORCEPROP 2 LAST BOM_COST SB
J 0
(-3400 -900);
DISPLAY 1.659574 (-3400 -900);
PAINT WHITE (-3400 -900);
DISPLAY INVISIBLE (-3400 -900);
FORCEPROP 2 LAST CDS_LIB dev_discrete
J 0
(-3450 -1050);
PAINT ORANGE (-3450 -1050);
DISPLAY INVISIBLE (-3450 -1050);
FORCEPROP 2 LAST CDS_SEC 1
J 0
(-3400 -900);
PAINT ORANGE (-3400 -900);
DISPLAY INVISIBLE (-3400 -900);
FORCEPROP 2 LAST SEC_TYPE 0402V
J 0
(-3400 -850);
DISPLAY 1.021277 (-3400 -850);
PAINT ORANGE (-3400 -850);
DISPLAY INVISIBLE (-3400 -850);
FORCEPROP 2 LAST SEC 1
J 0
(-3400 -850);
DISPLAY 0.680851 (-3400 -850);
PAINT MONO (-3400 -850);
DISPLAY INVISIBLE (-3400 -850);
FORCEPROP 1 LAST PATH I87
J 0
(-3400 -900);
DISPLAY 0.978723 (-3400 -900);
PAINT WHITE (-3400 -900);
DISPLAY INVISIBLE (-3400 -900);
FORCEPROP 2 LAST ROOM SB_FILTER_PLL0
J 0
(-3400 -900);
DISPLAY 1.659574 (-3400 -900);
PAINT WHITE (-3400 -900);
DISPLAY INVISIBLE (-3400 -900);
FORCEADD CAP_A..1
R 2
(-4300 -1050);
FORCEPROP 1 LASTPIN (-4300 -1150) $PN 2
J 2
(-4310 -1170);
DISPLAY 0.617021 (-4310 -1170);
PAINT ORANGE (-4310 -1170);
FORCEPROP 1 LASTPIN (-4300 -950) $PN 1
J 2
(-4310 -970);
DISPLAY 0.617021 (-4310 -970);
PAINT ORANGE (-4310 -970);
FORCEPROP 1 LAST MATERIAL X6S
J 2
(-4350 -1150);
DISPLAY 0.617021 (-4350 -1150);
PAINT SKYBLUE (-4350 -1150);
FORCEPROP 1 LAST VOLTAGE 6.3V
J 2
(-4350 -1050);
DISPLAY 0.617021 (-4350 -1050);
PAINT SKYBLUE (-4350 -1050);
FORCEPROP 1 LAST PACK_TYPE 0402V
J 2
(-4350 -1250);
DISPLAY 0.617021 (-4350 -1250);
PAINT SKYBLUE (-4350 -1250);
FORCEPROP 1 LAST TOLERANCE 10%
J 2
(-4350 -1100);
DISPLAY 0.617021 (-4350 -1100);
PAINT SKYBLUE (-4350 -1100);
FORCEPROP 1 LAST VALUE 1.0UF
J 2
(-4350 -1000);
DISPLAY 0.617021 (-4350 -1000);
PAINT SKYBLUE (-4350 -1000);
FORCEPROP 1 LAST PART_NUMBER D97712-004
J 2
(-4350 -1200);
DISPLAY 0.617021 (-4350 -1200);
PAINT BLUE (-4350 -1200);
FORCEPROP 1 LAST LOCATION C3M21
J 2
(-4350 -950);
DISPLAY 0.617021 (-4350 -950);
PAINT AQUA (-4350 -950);
FORCEPROP 1 LAST PATH I9
J 2
(-4350 -900);
DISPLAY 0.978723 (-4350 -900);
PAINT WHITE (-4350 -900);
DISPLAY INVISIBLE (-4350 -900);
FORCEPROP 2 LAST SEC 1
J 0
(-4350 -850);
PAINT MONO (-4350 -850);
DISPLAY INVISIBLE (-4350 -850);
FORCEPROP 2 LAST SEC_TYPE 0402V
J 0
(-4350 -850);
DISPLAY 1.021277 (-4350 -850);
PAINT ORANGE (-4350 -850);
DISPLAY INVISIBLE (-4350 -850);
FORCEPROP 2 LAST CDS_SEC 1
J 0
(-4350 -900);
PAINT ORANGE (-4350 -900);
DISPLAY INVISIBLE (-4350 -900);
FORCEPROP 2 LAST CDS_LIB dev_discrete
J 0
(-4300 -1050);
PAINT ORANGE (-4300 -1050);
DISPLAY INVISIBLE (-4300 -1050);
FORCEPROP 2 LAST BOM_COST SB
J 2
(-4350 -900);
DISPLAY 1.659574 (-4350 -900);
PAINT WHITE (-4350 -900);
DISPLAY INVISIBLE (-4350 -900);
FORCEPROP 2 LAST CDS_LOCATION C3M21
J 2
(-4350 -950);
DISPLAY 0.617021 (-4350 -950);
PAINT AQUA (-4350 -950);
DISPLAY INVISIBLE (-4350 -950);
FORCEPROP 2 LAST ROOM SB_FILTER_PLL0
J 2
(-4350 -900);
DISPLAY 1.659574 (-4350 -900);
PAINT WHITE (-4350 -900);
DISPLAY INVISIBLE (-4350 -900);
FORCEADD INTEL_CORP_BPAGE..1
(2775 -5050);
FORCEPROP 1 LAST CDS_CON_LAST_MODIFIED Tue Dec 01 11:51:59 2015
J 0
(1350 -4725);
DISPLAY 1.361702 (1350 -4725);
PAINT ORANGE (1350 -4725);
DISPLAY INVISIBLE (1350 -4725);
FORCEPROP 1 LAST CUSTOM_TXT_CDS <CURRENT_DESIGN_SHEET> OF <TOTAL_DESIGN_SHEETS>
J 0
(2275 -5025);
PAINT GREEN (2275 -5025);
FORCEPROP 2 LAST CUSTOM_TXT_CDS <XR_PAGE_TITLE>
J 0
(-5115 200);
DISPLAY 0.638298 (-5115 200);
PAINT PINK (-5115 200);
DISPLAY INVISIBLE (-5115 200);
FORCEPROP 2 LAST CUSTOM_TXT_CDS <CON_LAST_MODIFIED>
J 0
(850 -4700);
DISPLAY 1.361702 (850 -4700);
PAINT GREEN (850 -4700);
FORCEPROP 1 LAST SCH_TITLE LBG PLL FILTERS
J 0
(-5175 -5000);
DISPLAY 1.212766 (-5175 -5000);
PAINT ORANGE (-5175 -5000);
FORCEPROP 1 LAST SCH_ADDRESS1 2200 Mission College Blvd.
J 0
(-1200 -4925);
DISPLAY 0.617021 (-1200 -4925);
PAINT GREEN (-1200 -4925);
FORCEPROP 1 LAST SCH_ADDRESS2 P.O. BOX 58119
J 0
(-1200 -4975);
DISPLAY 0.617021 (-1200 -4975);
PAINT GREEN (-1200 -4975);
FORCEPROP 1 LAST SCH_ADDRESS3 Santa Clara, CA 95052-8119
J 0
(-1200 -5025);
DISPLAY 0.617021 (-1200 -5025);
PAINT GREEN (-1200 -5025);
FORCEPROP 1 LAST SCH_NUMBER H4694802
J 0
(1475 -4900);
DISPLAY 1.212766 (1475 -4900);
PAINT YELLOW (1475 -4900);
FORCEPROP 1 LAST SCH_DEPT BESD
J 1
(-1675 -4950);
DISPLAY 1.212766 (-1675 -4950);
PAINT YELLOW (-1675 -4950);
FORCEPROP 1 LAST SCH_REV 2.420
J 0
(2525 -4900);
DISPLAY 0.978723 (2525 -4900);
PAINT YELLOW (2525 -4900);
FORCEPROP 1 LAST COMMENT_BODY TRUE
J 0
(2787 -5038);
DISPLAY 0.617021 (2787 -5038);
PAINT GREEN (2787 -5038);
DISPLAY INVISIBLE (2787 -5038);
FORCEPROP 2 LAST CDS_LIB mstr_symbols
J 0
(2775 -5050);
DISPLAY 1.361702 (2775 -5050);
PAINT MONO (2775 -5050);
DISPLAY INVISIBLE (2775 -5050);
FORCEPROP 2 LAST PAGE_BORDER TRUE
J 0
(-5115 200);
DISPLAY 0.851064 (-5115 200);
PAINT PINK (-5115 200);
DISPLAY INVISIBLE (-5115 200);
FORCEPROP 2 LAST CDS_XR_PAGE_TITLE CR-127 : @BASEBOARD_FAB2_LIB.BASEBOARD_FAB2(SCH_1):PAGE127
J 0
(-5115 200);
DISPLAY 0.638298 (-5115 200);
PAINT PINK (-5115 200);
DISPLAY INVISIBLE (-5115 200);
WIRE 16 -1 (-4275 -2350)(-4275 -2500);
WIRE 16 -1 (-3425 -2500)(-4275 -2500);
WIRE 16 -1 (-3425 -2350)(-3425 -2500);
WIRE 16 -1 (-3425 -2550)(-3425 -2500);
WIRE 16 -1 (-4275 -2150)(-4275 -2050);
WIRE 16 -1 (-4275 -1750)(-4275 -2050);
WIRE 16 -1 (-4275 -2050)(-4125 -2050);
WIRE 16 -1 (-4250 -3650)(-4250 -3800);
WIRE 16 -1 (-3400 -3800)(-4250 -3800);
WIRE 16 -1 (-3400 -3650)(-3400 -3800);
WIRE 16 -1 (-3400 -3850)(-3400 -3800);
WIRE 16 -1 (-4250 -3450)(-4250 -3350);
WIRE 16 -1 (-4250 -3050)(-4250 -3350);
WIRE 16 -1 (-4250 -3350)(-4100 -3350);
WIRE 16 -1 (-2575 -1175)(-2575 -1275);
WIRE 16 -1 (-2575 -2425)(-2575 -2550);
WIRE 16 -1 (-2550 -3700)(-2550 -3800);
WIRE 16 -1 (-3900 -3350)(-3400 -3350);
WIRE 16 -1 (-3400 -3350)(-2550 -3350);
FORCEPROP 0 LAST VOLTAGE +1.05V
J 0
(-2950 -3300);
DISPLAY 1.021277 (-2950 -3300);
PAINT SKYBLUE (-2950 -3300);
DISPLAY INVISIBLE (-2950 -3300);
WIRE 16 -1 (-3400 -3450)(-3400 -3350);
WIRE 16 -1 (-2550 -3500)(-2550 -3350);
WIRE 16 -1 (-2550 -3025)(-2550 -3350);
WIRE 16 -1 (1250 -1175)(1400 -1175);
FORCEPROP 2 LAST VOLTAGE 1.05V
J 0
(1375 -1100);
PAINT SKYBLUE (1375 -1100);
DISPLAY INVISIBLE (1375 -1100);
WIRE 16 -1 (1400 -1175)(1850 -1175);
WIRE 16 -1 (1400 -1275)(1400 -1175);
WIRE 16 -1 (1850 -1275)(1850 -1175);
WIRE 16 -1 (1850 -800)(1850 -1175);
WIRE 16 -1 (950 -1175)(1050 -1175);
WIRE 16 -1 (950 -875)(950 -1175);
WIRE 16 -1 (950 -1175)(950 -1275);
WIRE 16 -1 (-1125 -1200)(-1000 -1200);
FORCEPROP 2 LAST VOLTAGE 1.05V
J 0
(-1000 -1125);
PAINT SKYBLUE (-1000 -1125);
DISPLAY INVISIBLE (-1000 -1125);
WIRE 16 -1 (-1125 -1200)(-1125 -1225);
WIRE 16 -1 (-1000 -1300)(-1000 -1200);
WIRE 16 -1 (-1000 -1200)(-500 -1200);
WIRE 16 -1 (-500 -850)(-500 -1200);
WIRE 16 -1 (-500 -1200)(-500 -1300);
WIRE 16 -1 (1850 -1475)(1850 -1625);
WIRE 16 -1 (1400 -1625)(1850 -1625);
WIRE 16 -1 (1400 -1475)(1400 -1625);
WIRE 16 -1 (1400 -1625)(1400 -1675);
WIRE 16 -1 (1250 -3075)(1400 -3075);
FORCEPROP 2 LAST VOLTAGE 1.05V
J 0
(1375 -3000);
PAINT SKYBLUE (1375 -3000);
DISPLAY INVISIBLE (1375 -3000);
WIRE 16 -1 (1400 -3075)(1700 -3075);
WIRE 16 -1 (1400 -3175)(1400 -3075);
WIRE 16 -1 (1700 -3075)(1700 -2750);
WIRE 16 -1 (1700 -3075)(1700 -3175);
WIRE 16 -1 (950 -3175)(950 -3075);
WIRE 16 -1 (950 -3075)(1050 -3075);
WIRE 16 -1 (950 -2775)(950 -3075);
WIRE 16 -1 (1700 -3375)(1700 -3575);
WIRE 16 -1 (1400 -3375)(1400 -3525);
WIRE 16 -1 (950 -3525)(1400 -3525);
WIRE 16 -1 (950 -3375)(950 -3525);
WIRE 16 -1 (950 -3525)(950 -3625);
WIRE 16 -1 (-4300 -1150)(-4300 -1300);
WIRE 16 -1 (-3450 -1300)(-4300 -1300);
WIRE 16 -1 (-3450 -1150)(-3450 -1300);
WIRE 16 -1 (-3450 -1350)(-3450 -1300);
WIRE 16 -1 (-500 -1500)(-500 -1650);
WIRE 16 -1 (-1000 -1650)(-500 -1650);
WIRE 16 -1 (-1000 -1500)(-1000 -1650);
WIRE 16 -1 (-1000 -1650)(-1000 -1700);
WIRE 16 -1 (-1150 -3100)(-1000 -3100);
FORCEPROP 2 LAST VOLTAGE 1.05V
J 0
(-1000 -3025);
PAINT SKYBLUE (-1000 -3025);
DISPLAY INVISIBLE (-1000 -3025);
WIRE 16 -1 (-1000 -3100)(-500 -3100);
WIRE 16 -1 (-1000 -3200)(-1000 -3100);
WIRE 16 -1 (-500 -3200)(-500 -3100);
WIRE 16 -1 (-500 -3100)(-500 -2700);
WIRE 16 -1 (-1000 -3400)(-1000 -3550);
WIRE 16 -1 (-500 -3550)(-1000 -3550);
WIRE 16 -1 (-500 -3400)(-500 -3550);
WIRE 16 -1 (-500 -3550)(-500 -3600);
WIRE 16 -1 (-1450 -900)(-1450 -1200);
WIRE 16 -1 (-1450 -1200)(-1325 -1200);
WIRE 16 -1 (-1450 -1200)(-1450 -1300);
WIRE 16 -1 (-4300 -950)(-4300 -850);
WIRE 16 -1 (-4300 -550)(-4300 -850);
WIRE 16 -1 (-4300 -850)(-4150 -850);
WIRE 16 -1 (-1450 -3200)(-1450 -3100);
WIRE 16 -1 (-1450 -2775)(-1450 -3100);
WIRE 16 -1 (-1450 -3100)(-1350 -3100);
WIRE 16 -1 (-3925 -2050)(-3425 -2050);
WIRE 16 -1 (-3425 -2050)(-2575 -2050);
FORCEPROP 0 LAST VOLTAGE +1.05V
J 0
(-2975 -2000);
DISPLAY 1.021277 (-2975 -2000);
PAINT SKYBLUE (-2975 -2000);
DISPLAY INVISIBLE (-2975 -2000);
WIRE 16 -1 (-3425 -2150)(-3425 -2050);
WIRE 16 -1 (-2575 -2225)(-2575 -2050);
WIRE 16 -1 (-2575 -1725)(-2575 -2050);
WIRE 16 -1 (-3950 -850)(-3450 -850);
WIRE 16 -1 (-3450 -850)(-2575 -850);
FORCEPROP 0 LAST VOLTAGE +1.05V
J 0
(-3000 -800);
DISPLAY 1.021277 (-3000 -800);
PAINT SKYBLUE (-3000 -800);
DISPLAY INVISIBLE (-3000 -800);
WIRE 16 -1 (-3450 -950)(-3450 -850);
WIRE 16 -1 (-2575 -975)(-2575 -850);
WIRE 16 -1 (-2575 -525)(-2575 -850);
WIRE 16 -1 (-1450 -1500)(-1450 -1700);
WIRE 16 -1 (950 -1475)(950 -1675);
WIRE 16 -1 (-1450 -3400)(-1450 -3575);
DOT 1 (-4300 -850);
DOT 1 (1700 -3075);
DOT 1 (1400 -3075);
DOT 1 (-1000 -3100);
DOT 1 (-2550 -3350);
DOT 1 (-2575 -850);
DOT 1 (-3450 -850);
DOT 1 (-3450 -1300);
DOT 1 (-2575 -2050);
DOT 1 (-3425 -2050);
DOT 1 (-3425 -2500);
DOT 1 (-3400 -3350);
DOT 1 (-3400 -3800);
DOT 1 (-4275 -2050);
DOT 1 (-4250 -3350);
DOT 1 (1850 -1175);
DOT 1 (1400 -1175);
DOT 1 (1400 -1625);
DOT 1 (950 -3075);
DOT 1 (950 -3525);
DOT 1 (-500 -1200);
DOT 1 (-1000 -1200);
DOT 1 (-1000 -1650);
DOT 1 (-500 -3100);
DOT 1 (-500 -3550);
DOT 1 (-1450 -1200);
DOT 1 (950 -1175);
DOT 1 (-1450 -3100);
FORCENOTE
ROOM=SB_FILTER_WM26
(-1400 -1972) 0;
DISPLAY LEFT (-1400 -1972);
PAINT PURPLE (-1400 -1972);
FORCENOTE
ROOM=SB_FILTER_WM20
(975 -1872) 0;
DISPLAY LEFT (975 -1872);
PAINT PURPLE (975 -1872);
FORCENOTE
ROOM=SB
(-4975 -4750) 0;
DISPLAY LEFT (-4975 -4750);
DISPLAY 1.021277 (-4975 -4750);
PAINT PURPLE (-4975 -4750);
FORCENOTE
ROOM=SB_FILTER_XTAL
(-3275 -3975) 0;
DISPLAY LEFT (-3275 -3975);
DISPLAY 0.808511 (-3275 -3975);
PAINT PURPLE (-3275 -3975);
FORCENOTE
ROOM=SB_FILTER_PLL1
(-3350 -2625) 0;
DISPLAY LEFT (-3350 -2625);
DISPLAY 0.808511 (-3350 -2625);
PAINT PURPLE (-3350 -2625);
FORCENOTE
ROOM=SB_FILTER_PLL0
(-3300 -1425) 0;
DISPLAY LEFT (-3300 -1425);
DISPLAY 0.808511 (-3300 -1425);
PAINT PURPLE (-3300 -1425);
FORCENOTE
ROOM=SB_FILTER_KR_PLL
(-1425 -3822) 0;
DISPLAY LEFT (-1425 -3822);
PAINT PURPLE (-1425 -3822);
FORCENOTE
ROOM=SB_FILTER_ISCLK
(975 -3797) 0;
DISPLAY LEFT (975 -3797);
PAINT PURPLE (975 -3797);
QUIT
